G04 ================== begin FILE IDENTIFICATION RECORD ==================*
G04 Layout Name:  DA0T6MTH8C0_t6m_tray_bp_c_brd_103112_274.brd*
G04 Film Name:    panel*
G04 File Format:  Gerber RS274X*
G04 File Origin:  Cadence Allegro 16.3-S048*
G04 Origin Date:  Tue Nov 26 11:26:41 2013*
G04 *
G04 Layer:  MANUFACTURING/PHOTOPLOT_OUTLINE*
G04 Layer:  DRAWING FORMAT/TITLE_BLOCK*
G04 Layer:  DRAWING FORMAT/TITLE_DATA_PANEL*
G04 Layer:  BOARD GEOMETRY/ASSEMBLY_NOTES*
G04 *
G04 Offset:    (0.00 0.00)*
G04 Mirror:    No*
G04 Mode:      Positive*
G04 Rotation:  0*
G04 FullContactRelief:  No*
G04 UndefLineWidth:     6.00*
G04 ================== end FILE IDENTIFICATION RECORD ====================*
%FSLAX25Y25*MOIN*%
%IR0*IPPOS*OFA0.00000B0.00000*MIA0B0*SFA1.00000B1.00000*%
%ADD10C,.006*%
G75*
%LPD*%
G75*
G36*
G01X-49213Y700392D02*
G02I-1968J0D01*
G37*
G36*
G01X1741378Y-150787D02*
G02I-1969J0D01*
G37*
G36*
G01X1871182Y-83790D02*
G02I-1969J0D01*
G37*
G54D10*
G01X-69633Y743993D02*
X-177889Y747473D01*
G01X-166600Y759917D02*
X-166359Y767413D01*
X-164027Y767338D01*
X-163293Y766939D01*
X-162842Y766425D01*
X-162688Y765419D01*
X-162907Y764426D01*
X-163487Y763819D01*
X-164152Y763465D01*
X-166484Y763540D01*
G01X-164152Y763465D02*
X-162869Y759797D01*
G01X-158810Y765920D02*
X-158226Y766651D01*
X-157561Y767005D01*
X-156811Y767106D01*
X-155886Y766826D01*
X-155253Y766181D01*
X-155091Y765425D01*
X-155208Y764678D01*
X-155601Y764066D01*
X-157507Y762876D01*
X-158375Y762029D01*
X-158975Y760797D01*
X-159197Y759679D01*
X-155279Y759553D01*
G01X-152541Y759465D02*
X-152380Y764462D01*
G01X-152425Y763088D02*
X-152125Y763704D01*
X-151642Y764188D01*
X-150981Y764417D01*
X-150336Y764146D01*
X-149886Y763632D01*
X-149626Y762998D01*
X-149743Y759375D01*
G01X-149626Y762998D02*
X-149326Y763614D01*
X-148844Y764099D01*
X-148183Y764327D01*
X-147538Y764057D01*
X-147087Y763542D01*
X-146831Y762783D01*
X-146944Y759285D01*
G01X-145045Y759224D02*
X-144884Y764221D01*
G01X-144929Y762847D02*
X-144629Y763463D01*
X-144146Y763947D01*
X-143485Y764176D01*
X-142840Y763905D01*
X-142390Y763391D01*
X-142130Y762757D01*
X-142247Y759134D01*
G01X-142130Y762757D02*
X-141830Y763373D01*
X-141348Y763858D01*
X-140687Y764086D01*
X-140042Y763816D01*
X-139591Y763301D01*
X-139335Y762542D01*
X-139448Y759044D01*
G01X-168001Y747456D02*
X-168894Y748736D01*
X-169320Y750000D01*
X-169160Y754997D01*
X-168653Y756232D01*
X-167680Y757451D01*
G01X-159967Y749449D02*
X-160149Y749580D01*
X-160141Y749830D01*
X-159951Y749949D01*
X-159768Y749818D01*
X-159776Y749568D01*
X-159967Y749449D01*
G01X-152222Y756954D02*
X-152976Y756728D01*
X-153556Y756122D01*
X-153953Y755384D01*
X-154265Y754393D01*
X-154394Y753272D01*
X-154337Y752145D01*
X-154089Y751136D01*
X-153740Y750374D01*
X-153201Y749732D01*
X-152463Y749458D01*
X-151708Y749684D01*
X-151128Y750290D01*
X-150731Y751028D01*
X-150419Y752019D01*
X-150290Y753140D01*
X-150347Y754267D01*
X-150595Y755276D01*
X-150944Y756038D01*
X-151483Y756680D01*
X-152222Y756954D01*
G01X-144967Y749217D02*
X-144309Y749321D01*
X-143551Y749672D01*
X-143065Y750281D01*
X-142850Y751150D01*
X-143008Y752030D01*
X-143544Y752798D01*
X-144372Y753200D01*
X-145304Y753230D01*
X-145856Y753498D01*
X-146303Y754137D01*
X-146461Y755018D01*
X-146153Y755884D01*
X-145480Y756487D01*
X-144726Y756713D01*
X-143987Y756439D01*
X-143354Y755794D01*
X-143103Y754910D01*
X-143317Y754041D01*
X-143804Y753432D01*
X-144372Y753200D01*
X-145304Y753230D01*
X-146156Y752882D01*
X-146740Y752150D01*
X-146954Y751282D01*
X-146796Y750401D01*
X-146350Y749762D01*
X-145615Y749363D01*
X-144967Y749217D01*
G01X-137310Y753973D02*
X-137471Y748976D01*
G01X-137246Y755972D02*
X-137428Y756103D01*
X-137420Y756353D01*
X-137230Y756472D01*
X-137047Y756341D01*
X-137055Y756091D01*
X-137246Y755972D01*
G01X-131560Y748786D02*
X-131400Y753783D01*
G01X-131440Y752534D02*
X-131047Y753147D01*
X-130471Y753628D01*
X-129720Y753729D01*
X-129072Y753583D01*
X-128528Y753066D01*
X-128276Y752182D01*
X-128389Y748684D01*
G01X-120845Y752819D02*
X-121482Y753339D01*
X-122038Y753482D01*
X-122792Y753256D01*
X-123368Y752775D01*
X-123769Y751912D01*
X-123891Y751041D01*
X-123825Y750163D01*
X-123477Y749401D01*
X-122937Y748759D01*
X-122199Y748485D01*
X-121538Y748714D01*
X-120962Y749196D01*
G01X-116568Y748304D02*
X-116327Y755800D01*
G01X-116444Y752177D02*
X-115957Y752787D01*
X-115479Y753146D01*
X-114728Y753247D01*
X-114173Y753104D01*
X-113536Y752584D01*
X-113280Y751825D01*
X-113397Y748202D01*
G01X-107100Y745498D02*
X-106127Y746718D01*
X-105621Y747952D01*
X-105460Y752949D01*
X-105886Y754214D01*
X-106779Y755493D01*
G01X-85452Y742040D02*
X-69633Y743993D01*
X-85294Y746959D01*
X-85452Y742040D01*
G01X-39370Y-168716D02*
Y-217716D01*
X-62992D01*
G02X-70866Y-209842I0J7874D01*
G01Y-168716D01*
G01D02*
Y686636D01*
G01D02*
Y739762D01*
G02X-62992Y747636I7874J0D01*
G01X-70866Y742762D02*
Y822700D01*
G01Y757479D02*
Y827715D01*
G01X-62992Y747636D02*
X-39370D01*
Y686636D01*
G01X783875Y819700D02*
X-70866D01*
G01X-65866Y820700D02*
X-70866Y819700D01*
X-65866Y818700D01*
Y820700D01*
G01X1727598Y-138716D02*
X1696102D01*
Y202323D01*
G03X1692165Y206260I-3937J0D01*
G01X1514000D01*
Y213858D01*
X244409D01*
Y249212D01*
X-35433D01*
G03X-39370Y245275I0J-3937D01*
G01Y153220D01*
X-7874D01*
Y-168503D01*
X-39370D01*
G01X1727598Y696636D02*
X1696102D01*
Y376700D01*
X1727598D01*
Y284645D01*
G02X1723661Y280708I-3937J0D01*
G01X1443819D01*
Y316062D01*
X175700D01*
Y323660D01*
X-3937D01*
G02X-7874Y327597I0J3937D01*
G01Y686636D01*
X-39370D01*
G01X-31496Y750626D02*
Y787026D01*
G01X4724Y-173228D02*
Y-198386D01*
G03X12598Y-206260I7874J0D01*
G01X184330D01*
X185822Y-206553D01*
X187091Y-207390D01*
X187949Y-208646D01*
X188298Y-210142D01*
X188567Y-211428D01*
X189420Y-212705D01*
X190698Y-213559D01*
X192204Y-213858D01*
X219763D01*
G03X223700Y-209921I0J3937D01*
G01Y-207874D01*
G02X227637Y-203937I3937J0D01*
G01X286693D01*
G02X290630Y-207874I0J-3937D01*
G01Y-209921D01*
G03X294567Y-213858I3937J0D01*
G01X369055D01*
G03X372992Y-209921I0J3937D01*
G01Y-207874D01*
G02X376929Y-203937I3937J0D01*
G01X435984D01*
G02X439921Y-207874I0J-3937D01*
G01Y-209921D01*
G03X443858Y-213858I3937J0D01*
G01X881181D01*
X882687Y-213559D01*
X883965Y-212705D01*
X884818Y-211428D01*
X885087Y-210142D01*
X885436Y-208646D01*
X886294Y-207390D01*
X887563Y-206553D01*
X889055Y-206260D01*
X1054409D01*
X1055901Y-206553D01*
X1057170Y-207390D01*
X1058028Y-208646D01*
X1058377Y-210142D01*
X1058646Y-211428D01*
X1059499Y-212705D01*
X1060777Y-213559D01*
X1062283Y-213858D01*
X1089842D01*
G03X1093779Y-209921I0J3937D01*
G01Y-207874D01*
G02X1097716Y-203937I3937J0D01*
G01X1156771D01*
G02X1160708Y-207874I0J-3937D01*
G01Y-209921D01*
G03X1164645Y-213858I3937J0D01*
G01X1239134D01*
G03X1243071Y-209921I0J3937D01*
G01Y-207874D01*
G02X1247008Y-203937I3937J0D01*
G01X1306063D01*
G02X1310000Y-207874I0J-3937D01*
G01Y-209921D01*
G03X1313937Y-213858I3937J0D01*
G01X1459567D01*
G03X1467441Y-205984I0J7874D01*
G01Y-178425D01*
G02X1471378Y-174488I3937J0D01*
G01X1479252D01*
G02X1483189Y-178425I0J-3937D01*
G01Y-211811D01*
X1489094Y-217716D01*
X1638425D01*
X1644330Y-211811D01*
Y-175787D01*
G02X1647086I1378J0D01*
G01Y-211811D01*
X1651023Y-215748D01*
X1652992Y-217716D01*
X1682322D01*
X1684291Y-215748D01*
X1688228Y-211811D01*
Y-15748D01*
G03X1680354Y-7874I-7874J0D01*
G01X7874D01*
G03X0Y-15748I0J-7874D01*
G01Y-47244D01*
G03X1968Y-49213I1969J0D01*
G01X2756D01*
G02X4724Y-51181I0J-1968D01*
G01Y-129921D01*
G03X6693Y-131890I1969J0D01*
G01X12992D01*
G02X14960Y-133858I0J-1968D01*
G01Y-169291D01*
G02X12992Y-171260I-1968J-1D01*
G01X6693D01*
G03X4724Y-173228I-1J-1968D01*
G01X-7874Y-42288D02*
G02X0I3937J0D01*
G01X-7874D02*
G02X0I3937J0D01*
G01X-7874Y-22603D02*
G03X0I3937J0D01*
G01X-7874D02*
G03X0I3937J0D01*
G01X1683504Y165354D02*
Y190512D01*
G03X1675630Y198386I-7874J0D01*
G01X1503898D01*
X1502406Y198679D01*
X1501137Y199516D01*
X1500279Y200772D01*
X1499930Y202268D01*
X1499661Y203554D01*
X1498808Y204831D01*
X1497530Y205685D01*
X1496024Y205984D01*
X1468465D01*
G03X1464528Y202047I0J-3937D01*
G01Y200000D01*
G02X1460591Y196063I-3937J0D01*
G01X1401535D01*
G02X1397598Y200000I0J3937D01*
G01Y202047D01*
G03X1393661Y205984I-3937J0D01*
G01X1319173D01*
G03X1315236Y202047I0J-3937D01*
G01Y200000D01*
G02X1311299Y196063I-3937J0D01*
G01X1252244D01*
G02X1248307Y200000I0J3937D01*
G01Y202047D01*
G03X1244370Y205984I-3937J0D01*
G01X807047D01*
X805541Y205685D01*
X804263Y204831D01*
X803410Y203554D01*
X803141Y202268D01*
X802792Y200772D01*
X801934Y199516D01*
X800665Y198679D01*
X799173Y198386D01*
X633819D01*
X632327Y198679D01*
X631058Y199516D01*
X630200Y200772D01*
X629851Y202268D01*
X629582Y203554D01*
X628729Y204831D01*
X627451Y205685D01*
X625945Y205984D01*
X598386D01*
G03X594449Y202047I0J-3937D01*
G01Y200000D01*
G02X590512Y196063I-3937J0D01*
G01X531457D01*
G02X527520Y200000I0J3937D01*
G01Y202047D01*
G03X523583Y205984I-3937J0D01*
G01X449094D01*
G03X445157Y202047I0J-3937D01*
G01Y200000D01*
G02X441220Y196063I-3937J0D01*
G01X382165D01*
G02X378228Y200000I0J3937D01*
G01Y202047D01*
G03X374291Y205984I-3937J0D01*
G01X228661D01*
G03X220787Y198110I0J-7874D01*
G01Y170551D01*
G02X216850Y166614I-3937J0D01*
G01X208976D01*
G02X205039Y170551I0J3937D01*
G01Y203937D01*
X199134Y209842D01*
X49803D01*
X43898Y203937D01*
Y167913D01*
G02X41142I-1378J0D01*
G01Y203937D01*
X37205Y207874D01*
X35236Y209842D01*
X5906D01*
X3937Y207874D01*
X0Y203937D01*
Y7874D01*
G03X7874Y0I7874J0D01*
G01X1680354D01*
G03X1688228Y7874I0J7874D01*
G01Y39370D01*
G03X1686260Y41339I-1969J0D01*
G01X1685472D01*
G02X1683504Y43307I0J1968D01*
G01Y122047D01*
G03X1681535Y124016I-1969J0D01*
G01X1675236D01*
G02X1673268Y125984I0J1968D01*
G01Y161417D01*
G02X1675236Y163386I1968J1D01*
G01X1681535D01*
G03X1683504Y165354I1J1968D01*
G01X-7872Y50112D02*
G02X2I3937J0D01*
G01X-7872D02*
G02X2I3937J0D01*
G01X-7872Y69797D02*
G03X2I3937J0D01*
G01X-7872D02*
G03X2I3937J0D01*
G01X10433Y114173D02*
Y128497D01*
G02X25000I7283J9298D01*
G01Y114173D01*
G02X10433I-7284J0D01*
G01X4724Y364566D02*
Y339408D01*
G03X12598Y331534I7874J0D01*
G01X184330D01*
X185822Y331241D01*
X187091Y330404D01*
X187949Y329148D01*
X188298Y327652D01*
X188567Y326366D01*
X189420Y325089D01*
X190698Y324235D01*
X192204Y323936D01*
X219763D01*
G03X223700Y327873I0J3937D01*
G01Y329920D01*
G02X227637Y333857I3937J0D01*
G01X286693D01*
G02X290630Y329920I0J-3937D01*
G01Y327873D01*
G03X294567Y323936I3937J0D01*
G01X369055D01*
G03X372992Y327873I0J3937D01*
G01Y329920D01*
G02X376929Y333857I3937J0D01*
G01X435984D01*
G02X439921Y329920I0J-3937D01*
G01Y327873D01*
G03X443858Y323936I3937J0D01*
G01X881181D01*
X882687Y324235D01*
X883965Y325089D01*
X884818Y326366D01*
X885087Y327652D01*
X885436Y329148D01*
X886294Y330404D01*
X887563Y331241D01*
X889055Y331534D01*
X1054409D01*
X1055901Y331241D01*
X1057170Y330404D01*
X1058028Y329148D01*
X1058377Y327652D01*
X1058646Y326366D01*
X1059499Y325089D01*
X1060777Y324235D01*
X1062283Y323936D01*
X1089842D01*
G03X1093779Y327873I0J3937D01*
G01Y329920D01*
G02X1097716Y333857I3937J0D01*
G01X1156771D01*
G02X1160708Y329920I0J-3937D01*
G01Y327873D01*
G03X1164645Y323936I3937J0D01*
G01X1239134D01*
G03X1243071Y327873I0J3937D01*
G01Y329920D01*
G02X1247008Y333857I3937J0D01*
G01X1306063D01*
G02X1310000Y329920I0J-3937D01*
G01Y327873D01*
G03X1313937Y323936I3937J0D01*
G01X1459567D01*
G03X1467441Y331810I0J7874D01*
G01Y359369D01*
G02X1471378Y363306I3937J0D01*
G01X1479252D01*
G02X1483189Y359369I0J-3937D01*
G01Y325983D01*
X1489094Y320078D01*
X1638425D01*
X1644330Y325983D01*
Y362007D01*
G02X1647086I1378J0D01*
G01Y325983D01*
X1651023Y322046D01*
X1652992Y320078D01*
X1682322D01*
X1684291Y322046D01*
X1688228Y325983D01*
Y522046D01*
G03X1680354Y529920I-7874J0D01*
G01X7874D01*
G03X0Y522046I0J-7874D01*
G01Y490550D01*
G03X1968Y488581I1969J0D01*
G01X2756D01*
G02X4724Y486613I0J-1968D01*
G01Y407873D01*
G03X6693Y405904I1969J0D01*
G01X12992D01*
G02X14960Y403936I0J-1968D01*
G01Y368503D01*
G02X12992Y366534I-1968J-1D01*
G01X6693D01*
G03X4724Y364566I-1J-1968D01*
G01X-7872Y516697D02*
G03X2I3937J0D01*
G01X-7872D02*
G03X2I3937J0D01*
G01X-7872Y497012D02*
G02X2I3937J0D01*
G01X-7872D02*
G02X2I3937J0D01*
G01X1683504Y703148D02*
Y728306D01*
G03X1675630Y736180I-7874J0D01*
G01X1503898D01*
X1502406Y736473D01*
X1501137Y737310D01*
X1500279Y738566D01*
X1499930Y740062D01*
X1499661Y741348D01*
X1498808Y742625D01*
X1497530Y743479D01*
X1496024Y743778D01*
X1468465D01*
G03X1464528Y739841I0J-3937D01*
G01Y737794D01*
G02X1460591Y733857I-3937J0D01*
G01X1401535D01*
G02X1397598Y737794I0J3937D01*
G01Y739841D01*
G03X1393661Y743778I-3937J0D01*
G01X1319173D01*
G03X1315236Y739841I0J-3937D01*
G01Y737794D01*
G02X1311299Y733857I-3937J0D01*
G01X1252244D01*
G02X1248307Y737794I0J3937D01*
G01Y739841D01*
G03X1244370Y743778I-3937J0D01*
G01X807047D01*
X805541Y743479D01*
X804263Y742625D01*
X803410Y741348D01*
X803141Y740062D01*
X802792Y738566D01*
X801934Y737310D01*
X800665Y736473D01*
X799173Y736180D01*
X633819D01*
X632327Y736473D01*
X631058Y737310D01*
X630200Y738566D01*
X629851Y740062D01*
X629582Y741348D01*
X628729Y742625D01*
X627451Y743479D01*
X625945Y743778D01*
X598386D01*
G03X594449Y739841I0J-3937D01*
G01Y737794D01*
G02X590512Y733857I-3937J0D01*
G01X531457D01*
G02X527520Y737794I0J3937D01*
G01Y739841D01*
G03X523583Y743778I-3937J0D01*
G01X449094D01*
G03X445157Y739841I0J-3937D01*
G01Y737794D01*
G02X441220Y733857I-3937J0D01*
G01X382165D01*
G02X378228Y737794I0J3937D01*
G01Y739841D01*
G03X374291Y743778I-3937J0D01*
G01X228661D01*
G03X220787Y735904I0J-7874D01*
G01Y708345D01*
G02X216850Y704408I-3937J0D01*
G01X208976D01*
G02X205039Y708345I0J3937D01*
G01Y741731D01*
X199134Y747636D01*
X49803D01*
X43898Y741731D01*
Y705707D01*
G02X41142I-1378J0D01*
G01Y741731D01*
X37205Y745668D01*
X35236Y747636D01*
X5906D01*
X3937Y745668D01*
X0Y741731D01*
Y545668D01*
G03X7874Y537794I7874J0D01*
G01X1680354D01*
G03X1688228Y545668I0J7874D01*
G01Y577164D01*
G03X1686260Y579133I-1969J0D01*
G01X1685472D01*
G02X1683504Y581101I0J1968D01*
G01Y659841D01*
G03X1681535Y661810I-1969J0D01*
G01X1675236D01*
G02X1673268Y663778I0J1968D01*
G01Y699211D01*
G02X1675236Y701180I1968J1D01*
G01X1681535D01*
G03X1683504Y703148I1J1968D01*
G01X-7874Y608423D02*
G02X0I3937J0D01*
G01X-7874Y628108D02*
G03X0I3937J0D01*
G01X-7874Y608423D02*
G02X0I3937J0D01*
G01X-7874Y628108D02*
G03X0I3937J0D01*
G01X10433Y651967D02*
Y666291D01*
G02X25000I7283J9298D01*
G01Y651967D01*
G02X10433I-7284J0D01*
G01X95492Y323660D02*
G03Y331534I0J3937D01*
G01Y323660D02*
G03Y331534I0J3937D01*
G01X115177Y323660D02*
G02Y331534I0J3937D01*
G01Y323660D02*
G02Y331534I0J3937D01*
G01X156592Y-7874D02*
G03Y0I0J3937D01*
G01Y-7874D02*
G03Y0I0J3937D01*
G01Y529920D02*
G03Y537794I0J3937D01*
G01Y529920D02*
G03Y537794I0J3937D01*
G01X176277Y-7874D02*
G02Y0I0J3937D01*
G01Y-7874D02*
G02Y0I0J3937D01*
G01Y529920D02*
G02Y537794I0J3937D01*
G01Y529920D02*
G02Y537794I0J3937D01*
G01X306929Y163386D02*
Y177710D01*
G02X321496I7283J9298D01*
G01Y163386D01*
G02X306929I-7283J0D01*
G01Y701180D02*
Y715504D01*
G02X321496I7283J9298D01*
G01Y701180D01*
G02X306929I-7283J0D01*
G01X341292Y205984D02*
G03Y213858I0J3937D01*
G01Y205984D02*
G03Y213858I0J3937D01*
G01X360977Y205984D02*
G02Y213858I0J3937D01*
G01Y205984D02*
G02Y213858I0J3937D01*
G01X439392Y-7874D02*
G03Y0I0J3937D01*
G01Y-7874D02*
G03Y0I0J3937D01*
G01Y529920D02*
G03Y537794I0J3937D01*
G01Y529920D02*
G03Y537794I0J3937D01*
G01X457212Y-338900D02*
Y-343900D01*
G01X455755Y-338900D02*
X458669D01*
G01X463579Y-343900D02*
X461045D01*
Y-338900D01*
X463579D01*
G01X462565Y-341317D02*
X461045D01*
G01X466145Y-338900D02*
Y-343900D01*
X468679D01*
G01X472512Y-344067D02*
X472385Y-343983D01*
Y-343817D01*
X472512Y-343733D01*
X472639Y-343817D01*
Y-343983D01*
X472512Y-344067D01*
G01Y-341817D02*
X472385Y-341733D01*
Y-341567D01*
X472512Y-341483D01*
X472639Y-341567D01*
Y-341733D01*
X472512Y-341817D01*
G01X477295Y-345567D02*
X476662Y-344733D01*
X476345Y-343900D01*
Y-340567D01*
X476662Y-339733D01*
X477295Y-338900D01*
G01X482712D02*
X482205Y-339067D01*
X481825Y-339483D01*
X481572Y-339983D01*
X481382Y-340650D01*
X481319Y-341400D01*
X481382Y-342150D01*
X481572Y-342817D01*
X481825Y-343317D01*
X482205Y-343733D01*
X482712Y-343900D01*
X483219Y-343733D01*
X483599Y-343317D01*
X483852Y-342817D01*
X484042Y-342150D01*
X484105Y-341400D01*
X484042Y-340650D01*
X483852Y-339983D01*
X483599Y-339483D01*
X483219Y-339067D01*
X482712Y-338900D01*
G01X486419Y-342900D02*
X486799Y-343483D01*
X487305Y-343817D01*
X487875Y-343900D01*
X488382Y-343817D01*
X488889Y-343400D01*
X489205Y-342900D01*
X489269Y-342400D01*
X489142Y-341817D01*
X488699Y-341400D01*
X488255Y-341233D01*
X487685D01*
G01X488255D02*
X488635Y-340983D01*
X488952Y-340567D01*
X489079Y-340067D01*
X488952Y-339567D01*
X488635Y-339150D01*
X488065Y-338900D01*
X487495Y-338983D01*
X486925Y-339317D01*
G01X493229Y-345567D02*
X493862Y-344733D01*
X494179Y-343900D01*
Y-340567D01*
X493862Y-339733D01*
X493229Y-338900D01*
G01X496619Y-342900D02*
X496999Y-343483D01*
X497505Y-343817D01*
X498075Y-343900D01*
X498582Y-343817D01*
X499089Y-343400D01*
X499405Y-342900D01*
X499469Y-342400D01*
X499342Y-341817D01*
X498899Y-341400D01*
X498455Y-341233D01*
X497885D01*
G01X498455D02*
X498835Y-340983D01*
X499152Y-340567D01*
X499279Y-340067D01*
X499152Y-339567D01*
X498835Y-339150D01*
X498265Y-338900D01*
X497695Y-338983D01*
X497125Y-339317D01*
G01X501909Y-339733D02*
X502289Y-339233D01*
X502732Y-338983D01*
X503239Y-338900D01*
X503872Y-339067D01*
X504315Y-339483D01*
X504442Y-339983D01*
X504379Y-340483D01*
X504125Y-340900D01*
X502859Y-341733D01*
X502289Y-342317D01*
X501909Y-343150D01*
X501782Y-343900D01*
X504442D01*
G01X508085D02*
X508212Y-342817D01*
X508402Y-341900D01*
X508655Y-341067D01*
X508972Y-340150D01*
X509479Y-338900D01*
X506945D01*
G01X512489Y-342233D02*
X514135D01*
G01X517209Y-339733D02*
X517589Y-339233D01*
X518032Y-338983D01*
X518539Y-338900D01*
X519172Y-339067D01*
X519615Y-339483D01*
X519742Y-339983D01*
X519679Y-340483D01*
X519425Y-340900D01*
X518159Y-341733D01*
X517589Y-342317D01*
X517209Y-343150D01*
X517082Y-343900D01*
X519742D01*
G01X522119Y-342900D02*
X522499Y-343483D01*
X523005Y-343817D01*
X523575Y-343900D01*
X524082Y-343817D01*
X524589Y-343400D01*
X524905Y-342900D01*
X524969Y-342400D01*
X524842Y-341817D01*
X524399Y-341400D01*
X523955Y-341233D01*
X523385D01*
G01X523955D02*
X524335Y-340983D01*
X524652Y-340567D01*
X524779Y-340067D01*
X524652Y-339567D01*
X524335Y-339150D01*
X523765Y-338900D01*
X523195Y-338983D01*
X522625Y-339317D01*
G01X529372Y-343900D02*
Y-338900D01*
X527029Y-342483D01*
X530195D01*
G01X532319Y-343150D02*
X532699Y-343567D01*
X533142Y-343817D01*
X533712Y-343900D01*
X534282Y-343733D01*
X534725Y-343400D01*
X535042Y-342817D01*
X535105Y-342150D01*
X534979Y-341483D01*
X534662Y-341067D01*
X534219Y-340733D01*
X533775Y-340650D01*
X533332Y-340733D01*
X532762Y-341067D01*
X532952Y-338900D01*
X534662D01*
G01X542709Y-343900D02*
Y-338900D01*
X545115D01*
G01X544229Y-341317D02*
X542709D01*
G01X547429Y-343900D02*
X549012Y-338900D01*
X550595Y-343900D01*
G01X550025Y-342150D02*
X547999D01*
G01X552782Y-343900D02*
X555442Y-338900D01*
G01X552782D02*
X555442Y-343900D01*
G01X559212Y-344067D02*
X559085Y-343983D01*
Y-343817D01*
X559212Y-343733D01*
X559339Y-343817D01*
Y-343983D01*
X559212Y-344067D01*
G01Y-341817D02*
X559085Y-341733D01*
Y-341567D01*
X559212Y-341483D01*
X559339Y-341567D01*
Y-341733D01*
X559212Y-341817D01*
G01X563995Y-345567D02*
X563362Y-344733D01*
X563045Y-343900D01*
Y-340567D01*
X563362Y-339733D01*
X563995Y-338900D01*
G01X569412D02*
X568905Y-339067D01*
X568525Y-339483D01*
X568272Y-339983D01*
X568082Y-340650D01*
X568019Y-341400D01*
X568082Y-342150D01*
X568272Y-342817D01*
X568525Y-343317D01*
X568905Y-343733D01*
X569412Y-343900D01*
X569919Y-343733D01*
X570299Y-343317D01*
X570552Y-342817D01*
X570742Y-342150D01*
X570805Y-341400D01*
X570742Y-340650D01*
X570552Y-339983D01*
X570299Y-339483D01*
X569919Y-339067D01*
X569412Y-338900D01*
G01X573119Y-342900D02*
X573499Y-343483D01*
X574005Y-343817D01*
X574575Y-343900D01*
X575082Y-343817D01*
X575589Y-343400D01*
X575905Y-342900D01*
X575969Y-342400D01*
X575842Y-341817D01*
X575399Y-341400D01*
X574955Y-341233D01*
X574385D01*
G01X574955D02*
X575335Y-340983D01*
X575652Y-340567D01*
X575779Y-340067D01*
X575652Y-339567D01*
X575335Y-339150D01*
X574765Y-338900D01*
X574195Y-338983D01*
X573625Y-339317D01*
G01X579929Y-345567D02*
X580562Y-344733D01*
X580879Y-343900D01*
Y-340567D01*
X580562Y-339733D01*
X579929Y-338900D01*
G01X583319Y-342900D02*
X583699Y-343483D01*
X584205Y-343817D01*
X584775Y-343900D01*
X585282Y-343817D01*
X585789Y-343400D01*
X586105Y-342900D01*
X586169Y-342400D01*
X586042Y-341817D01*
X585599Y-341400D01*
X585155Y-341233D01*
X584585D01*
G01X585155D02*
X585535Y-340983D01*
X585852Y-340567D01*
X585979Y-340067D01*
X585852Y-339567D01*
X585535Y-339150D01*
X584965Y-338900D01*
X584395Y-338983D01*
X583825Y-339317D01*
G01X588735Y-343317D02*
X589179Y-343733D01*
X589685Y-343900D01*
X590192Y-343733D01*
X590635Y-343233D01*
X590952Y-342483D01*
X591079Y-341733D01*
Y-340817D01*
X590952Y-340067D01*
X590635Y-339400D01*
X590255Y-339067D01*
X589812Y-338900D01*
X589305Y-339067D01*
X588925Y-339400D01*
X588672Y-339900D01*
X588545Y-340567D01*
X588672Y-341150D01*
X588989Y-341733D01*
X589369Y-342067D01*
X589812Y-342150D01*
X590319Y-341983D01*
X590699Y-341567D01*
X591079Y-340817D01*
G01X594785Y-343900D02*
X594912Y-342817D01*
X595102Y-341900D01*
X595355Y-341067D01*
X595672Y-340150D01*
X596179Y-338900D01*
X593645D01*
G01X599189Y-342233D02*
X600835D01*
G01X603719Y-342900D02*
X604099Y-343483D01*
X604605Y-343817D01*
X605175Y-343900D01*
X605682Y-343817D01*
X606189Y-343400D01*
X606505Y-342900D01*
X606569Y-342400D01*
X606442Y-341817D01*
X605999Y-341400D01*
X605555Y-341233D01*
X604985D01*
G01X605555D02*
X605935Y-340983D01*
X606252Y-340567D01*
X606379Y-340067D01*
X606252Y-339567D01*
X605935Y-339150D01*
X605365Y-338900D01*
X604795Y-338983D01*
X604225Y-339317D01*
G01X609009Y-341817D02*
X609452Y-341233D01*
X609832Y-340900D01*
X610339Y-340733D01*
X610782Y-340900D01*
X611099Y-341233D01*
X611352Y-341733D01*
X611415Y-342317D01*
X611352Y-342817D01*
X611099Y-343317D01*
X610719Y-343733D01*
X610275Y-343900D01*
X609769Y-343733D01*
X609325Y-343233D01*
X609072Y-342483D01*
X609009Y-341650D01*
X609135Y-340567D01*
X609325Y-339983D01*
X609642Y-339400D01*
X610085Y-338983D01*
X610529Y-338900D01*
X610972Y-339067D01*
X611289Y-339483D01*
G01X615312Y-343900D02*
Y-338900D01*
X614552Y-339900D01*
G01Y-343900D02*
X616072D01*
G01X621172D02*
Y-338900D01*
X618829Y-342483D01*
X621995D01*
G01X445212Y-273900D02*
Y-348900D01*
X945212D01*
Y-273900D01*
X445212D01*
G01X459077Y-7874D02*
G02Y0I0J3937D01*
G01Y-7874D02*
G02Y0I0J3937D01*
G01Y529920D02*
G02Y537794I0J3937D01*
G01Y529920D02*
G02Y537794I0J3937D01*
G01X511220Y-171260D02*
Y-185584D01*
G02X496653I-7283J-9298D01*
G01Y-171260D01*
G02X511220I7284J0D01*
G01Y366534D02*
Y352210D01*
G02X496653I-7283J-9298D01*
G01Y366534D01*
G02X511220I7284J0D01*
G01X593897Y-26378D02*
Y-40702D01*
G02X579330I-7283J-9298D01*
G01Y-26378D01*
G02X593897I7284J0D01*
G01Y511416D02*
Y497092D01*
G02X579330I-7283J-9298D01*
G01Y511416D01*
G02X593897I7284J0D01*
G01X640212Y-273900D02*
Y-348900D01*
G01Y-323900D02*
X743212D01*
Y-298900D01*
G01X640212D02*
X743212D01*
G01X682892Y316062D02*
G03Y323936I0J3937D01*
G01Y316062D02*
G03Y323936I0J3937D01*
G01X702577Y316062D02*
G02Y323936I0J3937D01*
G01Y316062D02*
G02Y323936I0J3937D01*
G01X743212Y-273900D02*
Y-348900D01*
G01X745212Y-273900D02*
Y-348900D01*
G01X750719Y-333900D02*
Y-328900D01*
X751985D01*
X752492Y-329150D01*
X752872Y-329483D01*
X753189Y-329983D01*
X753442Y-330567D01*
X753505Y-331400D01*
X753442Y-332233D01*
X753189Y-332817D01*
X752872Y-333317D01*
X752492Y-333650D01*
X751985Y-333900D01*
X750719D01*
G01X755629D02*
X757212Y-328900D01*
X758795Y-333900D01*
G01X758225Y-332150D02*
X756199D01*
G01X762312Y-328900D02*
Y-333900D01*
G01X760855Y-328900D02*
X763769D01*
G01X768679Y-333900D02*
X766145D01*
Y-328900D01*
X768679D01*
G01X767665Y-331317D02*
X766145D01*
G01X772512Y-334067D02*
X772385Y-333983D01*
Y-333817D01*
X772512Y-333733D01*
X772639Y-333817D01*
Y-333983D01*
X772512Y-334067D01*
G01Y-331817D02*
X772385Y-331733D01*
Y-331567D01*
X772512Y-331483D01*
X772639Y-331567D01*
Y-331733D01*
X772512Y-331817D01*
G01X745212Y-323900D02*
X945212D01*
G01X750845Y-308900D02*
Y-303900D01*
X752365D01*
X752872Y-304150D01*
X753252Y-304733D01*
X753379Y-305400D01*
X753252Y-306067D01*
X752935Y-306567D01*
X752365Y-306817D01*
X750845D01*
G01X756072Y-309067D02*
X758352Y-303900D01*
G01X760855Y-308900D02*
Y-303900D01*
X763769Y-308900D01*
Y-303900D01*
G01X767412Y-309067D02*
X767285Y-308983D01*
Y-308817D01*
X767412Y-308733D01*
X767539Y-308817D01*
Y-308983D01*
X767412Y-309067D01*
G01Y-306817D02*
X767285Y-306733D01*
Y-306567D01*
X767412Y-306483D01*
X767539Y-306567D01*
Y-306733D01*
X767412Y-306817D01*
G01X745212Y-298900D02*
X945212D01*
G01X750845Y-283900D02*
Y-278900D01*
X752365D01*
X752872Y-279150D01*
X753252Y-279733D01*
X753379Y-280400D01*
X753252Y-281067D01*
X752935Y-281567D01*
X752365Y-281817D01*
X750845D01*
G01X755945Y-283900D02*
Y-278900D01*
X757529D01*
X758035Y-279150D01*
X758352Y-279483D01*
X758479Y-280150D01*
X758352Y-280817D01*
X757972Y-281233D01*
X757529Y-281483D01*
X755945D01*
G01X757529D02*
X758479Y-283900D01*
G01X762312D02*
X761805Y-283817D01*
X761362Y-283483D01*
X760982Y-282983D01*
X760729Y-282400D01*
X760602Y-281733D01*
Y-281067D01*
X760729Y-280400D01*
X760982Y-279817D01*
X761362Y-279317D01*
X761805Y-278983D01*
X762312Y-278900D01*
X762819Y-278983D01*
X763262Y-279317D01*
X763642Y-279817D01*
X763895Y-280400D01*
X764022Y-281067D01*
Y-281733D01*
X763895Y-282400D01*
X763642Y-282983D01*
X763262Y-283483D01*
X762819Y-283817D01*
X762312Y-283900D01*
G01X766145Y-282900D02*
X766462Y-283400D01*
X766842Y-283733D01*
X767285Y-283900D01*
X767792Y-283733D01*
X768172Y-283400D01*
X768552Y-282900D01*
X768679Y-282233D01*
Y-278900D01*
G01X773779Y-283900D02*
X771245D01*
Y-278900D01*
X773779D01*
G01X772765Y-281317D02*
X771245D01*
G01X779005Y-279317D02*
X778625Y-279067D01*
X778182Y-278900D01*
X777675D01*
X777105Y-279150D01*
X776662Y-279567D01*
X776345Y-280067D01*
X776092Y-280900D01*
X776029Y-281650D01*
X776155Y-282400D01*
X776345Y-282900D01*
X776725Y-283400D01*
X777169Y-283733D01*
X777612Y-283900D01*
X778055D01*
X778499Y-283733D01*
X778879Y-283483D01*
X779195Y-283150D01*
G01X782712Y-278900D02*
Y-283900D01*
G01X781255Y-278900D02*
X784169D01*
G01X787812Y-284067D02*
X787685Y-283983D01*
Y-283817D01*
X787812Y-283733D01*
X787939Y-283817D01*
Y-283983D01*
X787812Y-284067D01*
G01Y-281817D02*
X787685Y-281733D01*
Y-281567D01*
X787812Y-281483D01*
X787939Y-281567D01*
Y-281733D01*
X787812Y-281817D01*
G01X776772Y18504D02*
Y32533D01*
G02X790551I6889J9593D01*
G01Y18504D01*
G02X776772I-6890J0D01*
G01Y556298D02*
Y570327D01*
G02X790551I6889J9593D01*
G01Y556298D01*
G02X776772I-6890J0D01*
G01X826892Y-7874D02*
G03Y0I0J3937D01*
G01Y-7874D02*
G03Y0I0J3937D01*
G01X819134Y163386D02*
Y177415D01*
G02X832913I6890J9593D01*
G01Y163386D01*
G02X819134I-6889J0D01*
G01X826892Y529920D02*
G03Y537794I0J3937D01*
G01Y529920D02*
G03Y537794I0J3937D01*
G01X819134Y701180D02*
Y715209D01*
G02X832913I6890J9593D01*
G01Y701180D01*
G02X819134I-6889J0D01*
G01X869094Y-171260D02*
Y-185289D01*
G02X855315I-6890J-9593D01*
G01Y-171260D01*
G02X869094I6889J0D01*
G01X846577Y-7874D02*
G02Y0I0J3937D01*
G01Y-7874D02*
G02Y0I0J3937D01*
G01X869094Y366534D02*
Y352505D01*
G02X855315I-6890J-9593D01*
G01Y366534D01*
G02X869094I6889J0D01*
G01X846577Y529920D02*
G02Y537794I0J3937D01*
G01Y529920D02*
G02Y537794I0J3937D01*
G01X842725Y819700D02*
X1759094D01*
G01X860212Y-323900D02*
Y-348900D01*
G01X865845Y-333900D02*
Y-328900D01*
X867429D01*
X867935Y-329150D01*
X868252Y-329483D01*
X868379Y-330150D01*
X868252Y-330817D01*
X867872Y-331233D01*
X867429Y-331483D01*
X865845D01*
G01X867429D02*
X868379Y-333900D01*
G01X873479D02*
X870945D01*
Y-328900D01*
X873479D01*
G01X872465Y-331317D02*
X870945D01*
G01X875729Y-328900D02*
X877312Y-333900D01*
X878895Y-328900D01*
G01X882412Y-334067D02*
X882285Y-333983D01*
Y-333817D01*
X882412Y-333733D01*
X882539Y-333817D01*
Y-333983D01*
X882412Y-334067D01*
G01Y-331817D02*
X882285Y-331733D01*
Y-331567D01*
X882412Y-331483D01*
X882539Y-331567D01*
Y-331733D01*
X882412Y-331817D01*
G01X911456Y-26378D02*
Y-40407D01*
G02X897677I-6889J-9593D01*
G01Y-26378D01*
G02X911456I6890J0D01*
G01Y511416D02*
Y497387D01*
G02X897677I-6889J-9593D01*
G01Y511416D01*
G02X911456I6890J0D01*
G01X909212Y-323900D02*
Y-348900D01*
G01X1019892Y205984D02*
G03Y213858I0J3937D01*
G01Y205984D02*
G03Y213858I0J3937D01*
G01X1039577Y205984D02*
G02Y213858I0J3937D01*
G01Y205984D02*
G02Y213858I0J3937D01*
G01X1094331Y18504D02*
Y32828D01*
G02X1108898I7283J9298D01*
G01Y18504D01*
G02X1094331I-7283J0D01*
G01Y556298D02*
Y570622D01*
G02X1108898I7283J9298D01*
G01Y556298D01*
G02X1094331I-7283J0D01*
G01X1177008Y163386D02*
Y177710D01*
G02X1191575I7284J9298D01*
G01Y163386D01*
G02X1177008I-7283J0D01*
G01Y701180D02*
Y715504D01*
G02X1191575I7284J9298D01*
G01Y701180D01*
G02X1177008I-7283J0D01*
G01X1252692Y-7874D02*
G03Y0I0J3937D01*
G01Y-7874D02*
G03Y0I0J3937D01*
G01X1272377Y-7874D02*
G02Y0I0J3937D01*
G01Y-7874D02*
G02Y0I0J3937D01*
G01Y529920D02*
G02Y537794I0J3937D01*
G01Y529920D02*
G02Y537794I0J3937D01*
G01X1252692Y529920D02*
G03Y537794I0J3937D01*
G01Y529920D02*
G03Y537794I0J3937D01*
G01X1381299Y-171260D02*
Y-185584D01*
G02X1366732I-7283J-9298D01*
G01Y-171260D01*
G02X1381299I7284J0D01*
G01Y366534D02*
Y352210D01*
G02X1366732I-7283J-9298D01*
G01Y366534D01*
G02X1381299I7284J0D01*
G01X1410992Y316062D02*
G03Y323936I0J3937D01*
G01Y316062D02*
G03Y323936I0J3937D01*
G01X1430677Y316062D02*
G02Y323936I0J3937D01*
G01Y316062D02*
G02Y323936I0J3937D01*
G01X1512292Y-7874D02*
G03Y0I0J3937D01*
G01Y-7874D02*
G03Y0I0J3937D01*
G01Y529920D02*
G03Y537794I0J3937D01*
G01Y529920D02*
G03Y537794I0J3937D01*
G01X1531977Y-7874D02*
G02Y0I0J3937D01*
G01Y-7874D02*
G02Y0I0J3937D01*
G01Y529920D02*
G02Y537794I0J3937D01*
G01Y529920D02*
G02Y537794I0J3937D01*
G01X1571192Y198386D02*
G03Y206260I0J3937D01*
G01Y198386D02*
G03Y206260I0J3937D01*
G01X1590877Y198386D02*
G02Y206260I0J3937D01*
G01Y198386D02*
G02Y206260I0J3937D01*
G01X1677795Y-122047D02*
Y-136371D01*
G02X1663228I-7283J-9298D01*
G01Y-122047D01*
G02X1677795I7284J0D01*
G01Y415747D02*
Y401423D01*
G02X1663228I-7283J-9298D01*
G01Y415747D01*
G02X1677795I7284J0D01*
G01X1685322Y-217716D02*
X1808400D01*
G01X1688228Y-98188D02*
G02X1696102I3937J0D01*
G01X1688228D02*
G02X1696102I3937J0D01*
G01X1688228Y-78503D02*
G03X1696102I3937J0D01*
G01X1688228D02*
G03X1696102I3937J0D01*
G01X1688228Y14612D02*
G02X1696102I3937J0D01*
G01X1688228D02*
G02X1696102I3937J0D01*
G01X1688228Y34297D02*
G03X1696102I3937J0D01*
G01X1688228D02*
G03X1696102I3937J0D01*
G01X1688228Y460612D02*
G02X1696102I3937J0D01*
G01X1688228D02*
G02X1696102I3937J0D01*
G01X1688228Y480297D02*
G03X1696102I3937J0D01*
G01X1688228D02*
G03X1696102I3937J0D01*
G01X1688228Y550467D02*
G02X1696102I3937J0D01*
G01X1688228D02*
G02X1696102I3937J0D01*
G01X1688228Y570152D02*
G03X1696102I3937J0D01*
G01X1688228D02*
G03X1696102I3937J0D01*
G01X1759094Y-138716D02*
Y-209842D01*
G02X1751220Y-217716I-7874J0D01*
G01X1727598D01*
Y-138716D01*
G01Y696636D02*
Y747636D01*
G01X1719724Y750626D02*
Y787026D01*
G01X1727598Y747636D02*
X1751220D01*
G02X1759094Y739762I0J-7874D01*
G01Y696636D01*
G01X1732300Y747636D02*
X1808400D01*
G01X1754094Y818700D02*
X1759094Y819700D01*
X1754094Y820700D01*
Y818700D01*
G01X1768937Y-217716D02*
X1808724D01*
G01X1759094Y696636D02*
Y-138716D01*
G01Y731306D02*
Y822700D01*
G01Y757479D02*
Y827715D01*
G01X1768937Y747636D02*
X1854409D01*
G01X1805400Y227325D02*
Y-217716D01*
G01X1804400Y-212716D02*
X1805400Y-217716D01*
X1806400Y-212716D01*
X1804400D01*
G01X1805400Y279875D02*
Y747636D01*
G01X1806400Y742636D02*
X1805400Y747636D01*
X1804400Y742636D01*
X1806400D01*
G01X1841935Y-122461D02*
X1842188Y-122211D01*
X1842378Y-121795D01*
X1842505Y-121211D01*
X1842378Y-120711D01*
X1842125Y-120378D01*
X1841681Y-120128D01*
X1839971D01*
Y-125128D01*
X1842061D01*
X1842505Y-124795D01*
X1842758Y-124295D01*
X1842885Y-123711D01*
X1842758Y-123128D01*
X1842378Y-122628D01*
X1841935Y-122461D01*
X1839971D01*
G01X1845641Y-125128D02*
Y-121795D01*
G01Y-122461D02*
X1845958Y-122128D01*
X1846275Y-121878D01*
X1846718Y-121795D01*
X1847035Y-121878D01*
X1847415Y-122128D01*
G01X1850678Y-122878D02*
X1852705D01*
X1852515Y-122295D01*
X1852198Y-121961D01*
X1851755Y-121795D01*
X1851311Y-121878D01*
X1850931Y-122128D01*
X1850678Y-122711D01*
X1850551Y-123211D01*
Y-123711D01*
X1850678Y-124211D01*
X1850995Y-124711D01*
X1851375Y-125045D01*
X1851818Y-125128D01*
X1852261Y-124961D01*
X1852705Y-124461D01*
G01X1857868Y-125128D02*
Y-121795D01*
G01Y-122378D02*
X1857615Y-122045D01*
X1857235Y-121878D01*
X1856791Y-121795D01*
X1856348Y-121961D01*
X1855968Y-122295D01*
X1855715Y-122795D01*
X1855588Y-123461D01*
X1855715Y-124128D01*
X1855968Y-124628D01*
X1856348Y-124961D01*
X1856791Y-125128D01*
X1857235Y-125045D01*
X1857615Y-124795D01*
X1857868Y-124461D01*
G01X1860751Y-125128D02*
Y-120128D01*
G01X1862778Y-121795D02*
X1860751Y-123711D01*
G01X1861575Y-122961D02*
X1862905Y-125128D01*
G01X1866928Y-120128D02*
Y-125128D01*
G01X1866041Y-121795D02*
X1867815D01*
G01X1873168Y-125128D02*
Y-121795D01*
G01Y-122378D02*
X1872915Y-122045D01*
X1872535Y-121878D01*
X1872091Y-121795D01*
X1871648Y-121961D01*
X1871268Y-122295D01*
X1871015Y-122795D01*
X1870888Y-123461D01*
X1871015Y-124128D01*
X1871268Y-124628D01*
X1871648Y-124961D01*
X1872091Y-125128D01*
X1872535Y-125045D01*
X1872915Y-124795D01*
X1873168Y-124461D01*
G01X1875988Y-125128D02*
Y-120128D01*
G01Y-122628D02*
X1876305Y-122128D01*
X1876685Y-121878D01*
X1877065Y-121795D01*
X1877635Y-121961D01*
X1878015Y-122295D01*
X1878268Y-122878D01*
Y-123545D01*
X1878141Y-124211D01*
X1877888Y-124711D01*
X1877445Y-125045D01*
X1877065Y-125128D01*
X1876685Y-125045D01*
X1876305Y-124795D01*
X1875988Y-124378D01*
G01X1882228Y-125295D02*
X1882101Y-125211D01*
Y-125045D01*
X1882228Y-124961D01*
X1882355Y-125045D01*
Y-125211D01*
X1882228Y-125295D01*
G01Y-123045D02*
X1882101Y-122961D01*
Y-122795D01*
X1882228Y-122711D01*
X1882355Y-122795D01*
Y-122961D01*
X1882228Y-123045D01*
G01X1916725Y-58598D02*
Y-53598D01*
X1919131D01*
G01X1918245Y-56015D02*
X1916725D01*
G01X1923028Y-58598D02*
X1922648Y-58515D01*
X1922268Y-58181D01*
X1922015Y-57598D01*
X1921888Y-56931D01*
X1922015Y-56265D01*
X1922268Y-55681D01*
X1922648Y-55348D01*
X1923028Y-55265D01*
X1923408Y-55348D01*
X1923788Y-55681D01*
X1924041Y-56265D01*
X1924105Y-56931D01*
X1924041Y-57598D01*
X1923788Y-58181D01*
X1923408Y-58515D01*
X1923028Y-58598D01*
G01X1927241D02*
Y-55265D01*
G01Y-55931D02*
X1927558Y-55598D01*
X1927875Y-55348D01*
X1928318Y-55265D01*
X1928635Y-55348D01*
X1929015Y-55598D01*
G01X1937061Y-58598D02*
Y-53598D01*
X1938581D01*
X1939088Y-53848D01*
X1939468Y-54431D01*
X1939595Y-55098D01*
X1939468Y-55765D01*
X1939151Y-56265D01*
X1938581Y-56515D01*
X1937061D01*
G01X1944568Y-58598D02*
Y-55265D01*
G01Y-55848D02*
X1944315Y-55515D01*
X1943935Y-55348D01*
X1943491Y-55265D01*
X1943048Y-55431D01*
X1942668Y-55765D01*
X1942415Y-56265D01*
X1942288Y-56931D01*
X1942415Y-57598D01*
X1942668Y-58098D01*
X1943048Y-58431D01*
X1943491Y-58598D01*
X1943935Y-58515D01*
X1944315Y-58265D01*
X1944568Y-57931D01*
G01X1947451Y-58598D02*
Y-55265D01*
G01Y-56098D02*
X1947705Y-55681D01*
X1948085Y-55348D01*
X1948591Y-55265D01*
X1949035Y-55348D01*
X1949415Y-55681D01*
X1949605Y-56265D01*
Y-58598D01*
G01X1952678Y-56348D02*
X1954705D01*
X1954515Y-55765D01*
X1954198Y-55431D01*
X1953755Y-55265D01*
X1953311Y-55348D01*
X1952931Y-55598D01*
X1952678Y-56181D01*
X1952551Y-56681D01*
Y-57181D01*
X1952678Y-57681D01*
X1952995Y-58181D01*
X1953375Y-58515D01*
X1953818Y-58598D01*
X1954261Y-58431D01*
X1954705Y-57931D01*
G01X1958728Y-58598D02*
Y-53598D01*
G01X1969435Y-55931D02*
X1969688Y-55681D01*
X1969878Y-55265D01*
X1970005Y-54681D01*
X1969878Y-54181D01*
X1969625Y-53848D01*
X1969181Y-53598D01*
X1967471D01*
Y-58598D01*
X1969561D01*
X1970005Y-58265D01*
X1970258Y-57765D01*
X1970385Y-57181D01*
X1970258Y-56598D01*
X1969878Y-56098D01*
X1969435Y-55931D01*
X1967471D01*
G01X1974028Y-58598D02*
X1973648Y-58515D01*
X1973268Y-58181D01*
X1973015Y-57598D01*
X1972888Y-56931D01*
X1973015Y-56265D01*
X1973268Y-55681D01*
X1973648Y-55348D01*
X1974028Y-55265D01*
X1974408Y-55348D01*
X1974788Y-55681D01*
X1975041Y-56265D01*
X1975105Y-56931D01*
X1975041Y-57598D01*
X1974788Y-58181D01*
X1974408Y-58515D01*
X1974028Y-58598D01*
G01X1980268D02*
Y-55265D01*
G01Y-55848D02*
X1980015Y-55515D01*
X1979635Y-55348D01*
X1979191Y-55265D01*
X1978748Y-55431D01*
X1978368Y-55765D01*
X1978115Y-56265D01*
X1977988Y-56931D01*
X1978115Y-57598D01*
X1978368Y-58098D01*
X1978748Y-58431D01*
X1979191Y-58598D01*
X1979635Y-58515D01*
X1980015Y-58265D01*
X1980268Y-57931D01*
G01X1983341Y-58598D02*
Y-55265D01*
G01Y-55931D02*
X1983658Y-55598D01*
X1983975Y-55348D01*
X1984418Y-55265D01*
X1984735Y-55348D01*
X1985115Y-55598D01*
G01X1990468Y-53598D02*
Y-58598D01*
G01Y-57848D02*
X1990215Y-58265D01*
X1989835Y-58515D01*
X1989391Y-58598D01*
X1988885Y-58431D01*
X1988505Y-58015D01*
X1988251Y-57515D01*
X1988188Y-56931D01*
X1988251Y-56348D01*
X1988505Y-55848D01*
X1988885Y-55431D01*
X1989391Y-55265D01*
X1989835Y-55348D01*
X1990151Y-55515D01*
X1990468Y-55848D01*
G01X1917928Y-40998D02*
Y-45998D01*
G01X1916471Y-40998D02*
X1919385D01*
G01X1923028Y-45998D02*
X1922648Y-45915D01*
X1922268Y-45581D01*
X1922015Y-44998D01*
X1921888Y-44331D01*
X1922015Y-43665D01*
X1922268Y-43081D01*
X1922648Y-42748D01*
X1923028Y-42665D01*
X1923408Y-42748D01*
X1923788Y-43081D01*
X1924041Y-43665D01*
X1924105Y-44331D01*
X1924041Y-44998D01*
X1923788Y-45581D01*
X1923408Y-45915D01*
X1923028Y-45998D01*
G01X1926988Y-47665D02*
Y-42665D01*
G01Y-43415D02*
X1927305Y-42998D01*
X1927621Y-42748D01*
X1928128Y-42665D01*
X1928571Y-42748D01*
X1929015Y-43165D01*
X1929205Y-43748D01*
X1929268Y-44331D01*
X1929205Y-44915D01*
X1929015Y-45498D01*
X1928635Y-45831D01*
X1928128Y-45998D01*
X1927685Y-45915D01*
X1927241Y-45665D01*
X1926988Y-45331D01*
G01X1936745Y-45998D02*
X1938328Y-40998D01*
X1939911Y-45998D01*
G01X1939341Y-44248D02*
X1937315D01*
G01X1942351Y-45998D02*
Y-42665D01*
G01Y-43498D02*
X1942605Y-43081D01*
X1942985Y-42748D01*
X1943491Y-42665D01*
X1943935Y-42748D01*
X1944315Y-43081D01*
X1944505Y-43665D01*
Y-45998D01*
G01X1949668Y-40998D02*
Y-45998D01*
G01Y-45248D02*
X1949415Y-45665D01*
X1949035Y-45915D01*
X1948591Y-45998D01*
X1948085Y-45831D01*
X1947705Y-45415D01*
X1947451Y-44915D01*
X1947388Y-44331D01*
X1947451Y-43748D01*
X1947705Y-43248D01*
X1948085Y-42831D01*
X1948591Y-42665D01*
X1949035Y-42748D01*
X1949351Y-42915D01*
X1949668Y-43248D01*
G01X1959235Y-43331D02*
X1959488Y-43081D01*
X1959678Y-42665D01*
X1959805Y-42081D01*
X1959678Y-41581D01*
X1959425Y-41248D01*
X1958981Y-40998D01*
X1957271D01*
Y-45998D01*
X1959361D01*
X1959805Y-45665D01*
X1960058Y-45165D01*
X1960185Y-44581D01*
X1960058Y-43998D01*
X1959678Y-43498D01*
X1959235Y-43331D01*
X1957271D01*
G01X1963828Y-45998D02*
X1963448Y-45915D01*
X1963068Y-45581D01*
X1962815Y-44998D01*
X1962688Y-44331D01*
X1962815Y-43665D01*
X1963068Y-43081D01*
X1963448Y-42748D01*
X1963828Y-42665D01*
X1964208Y-42748D01*
X1964588Y-43081D01*
X1964841Y-43665D01*
X1964905Y-44331D01*
X1964841Y-44998D01*
X1964588Y-45581D01*
X1964208Y-45915D01*
X1963828Y-45998D01*
G01X1968928Y-40998D02*
Y-45998D01*
G01X1968041Y-42665D02*
X1969815D01*
G01X1974028Y-40998D02*
Y-45998D01*
G01X1973141Y-42665D02*
X1974915D01*
G01X1979128Y-45998D02*
X1978748Y-45915D01*
X1978368Y-45581D01*
X1978115Y-44998D01*
X1977988Y-44331D01*
X1978115Y-43665D01*
X1978368Y-43081D01*
X1978748Y-42748D01*
X1979128Y-42665D01*
X1979508Y-42748D01*
X1979888Y-43081D01*
X1980141Y-43665D01*
X1980205Y-44331D01*
X1980141Y-44998D01*
X1979888Y-45581D01*
X1979508Y-45915D01*
X1979128Y-45998D01*
G01X1982328D02*
Y-42665D01*
G01Y-43581D02*
X1982518Y-43165D01*
X1982835Y-42831D01*
X1983278Y-42665D01*
X1983721Y-42831D01*
X1984038Y-43165D01*
X1984228Y-43581D01*
Y-45998D01*
G01Y-43581D02*
X1984418Y-43165D01*
X1984735Y-42831D01*
X1985178Y-42665D01*
X1985621Y-42831D01*
X1985938Y-43165D01*
X1986128Y-43665D01*
Y-45998D01*
G01X1993098Y-45331D02*
X1993605Y-45748D01*
X1994175Y-45998D01*
X1994681D01*
X1995188Y-45748D01*
X1995568Y-45331D01*
X1995758Y-44748D01*
X1995631Y-44165D01*
X1995315Y-43665D01*
X1994745Y-43331D01*
X1993985Y-43165D01*
X1993541Y-42831D01*
X1993351Y-42248D01*
X1993478Y-41665D01*
X1993795Y-41248D01*
X1994238Y-40998D01*
X1994681D01*
X1995125Y-41165D01*
X1995505Y-41581D01*
G01X1999528Y-42665D02*
Y-45998D01*
G01Y-41331D02*
X1999401Y-41248D01*
Y-41081D01*
X1999528Y-40998D01*
X1999655Y-41081D01*
Y-41248D01*
X1999528Y-41331D01*
G01X2005768Y-40998D02*
Y-45998D01*
G01Y-45248D02*
X2005515Y-45665D01*
X2005135Y-45915D01*
X2004691Y-45998D01*
X2004185Y-45831D01*
X2003805Y-45415D01*
X2003551Y-44915D01*
X2003488Y-44331D01*
X2003551Y-43748D01*
X2003805Y-43248D01*
X2004185Y-42831D01*
X2004691Y-42665D01*
X2005135Y-42748D01*
X2005451Y-42915D01*
X2005768Y-43248D01*
G01X2008778Y-43748D02*
X2010805D01*
X2010615Y-43165D01*
X2010298Y-42831D01*
X2009855Y-42665D01*
X2009411Y-42748D01*
X2009031Y-42998D01*
X2008778Y-43581D01*
X2008651Y-44081D01*
Y-44581D01*
X2008778Y-45081D01*
X2009095Y-45581D01*
X2009475Y-45915D01*
X2009918Y-45998D01*
X2010361Y-45831D01*
X2010805Y-45331D01*
G01X1916725Y-58598D02*
Y-53598D01*
X1919131D01*
G01X1918245Y-56015D02*
X1916725D01*
G01X1923028Y-58598D02*
X1922648Y-58515D01*
X1922268Y-58181D01*
X1922015Y-57598D01*
X1921888Y-56931D01*
X1922015Y-56265D01*
X1922268Y-55681D01*
X1922648Y-55348D01*
X1923028Y-55265D01*
X1923408Y-55348D01*
X1923788Y-55681D01*
X1924041Y-56265D01*
X1924105Y-56931D01*
X1924041Y-57598D01*
X1923788Y-58181D01*
X1923408Y-58515D01*
X1923028Y-58598D01*
G01X1927241D02*
Y-55265D01*
G01Y-55931D02*
X1927558Y-55598D01*
X1927875Y-55348D01*
X1928318Y-55265D01*
X1928635Y-55348D01*
X1929015Y-55598D01*
G01X1937061Y-58598D02*
Y-53598D01*
X1938581D01*
X1939088Y-53848D01*
X1939468Y-54431D01*
X1939595Y-55098D01*
X1939468Y-55765D01*
X1939151Y-56265D01*
X1938581Y-56515D01*
X1937061D01*
G01X1944568Y-58598D02*
Y-55265D01*
G01Y-55848D02*
X1944315Y-55515D01*
X1943935Y-55348D01*
X1943491Y-55265D01*
X1943048Y-55431D01*
X1942668Y-55765D01*
X1942415Y-56265D01*
X1942288Y-56931D01*
X1942415Y-57598D01*
X1942668Y-58098D01*
X1943048Y-58431D01*
X1943491Y-58598D01*
X1943935Y-58515D01*
X1944315Y-58265D01*
X1944568Y-57931D01*
G01X1947451Y-58598D02*
Y-55265D01*
G01Y-56098D02*
X1947705Y-55681D01*
X1948085Y-55348D01*
X1948591Y-55265D01*
X1949035Y-55348D01*
X1949415Y-55681D01*
X1949605Y-56265D01*
Y-58598D01*
G01X1952678Y-56348D02*
X1954705D01*
X1954515Y-55765D01*
X1954198Y-55431D01*
X1953755Y-55265D01*
X1953311Y-55348D01*
X1952931Y-55598D01*
X1952678Y-56181D01*
X1952551Y-56681D01*
Y-57181D01*
X1952678Y-57681D01*
X1952995Y-58181D01*
X1953375Y-58515D01*
X1953818Y-58598D01*
X1954261Y-58431D01*
X1954705Y-57931D01*
G01X1958728Y-58598D02*
Y-53598D01*
G01X1969435Y-55931D02*
X1969688Y-55681D01*
X1969878Y-55265D01*
X1970005Y-54681D01*
X1969878Y-54181D01*
X1969625Y-53848D01*
X1969181Y-53598D01*
X1967471D01*
Y-58598D01*
X1969561D01*
X1970005Y-58265D01*
X1970258Y-57765D01*
X1970385Y-57181D01*
X1970258Y-56598D01*
X1969878Y-56098D01*
X1969435Y-55931D01*
X1967471D01*
G01X1974028Y-58598D02*
X1973648Y-58515D01*
X1973268Y-58181D01*
X1973015Y-57598D01*
X1972888Y-56931D01*
X1973015Y-56265D01*
X1973268Y-55681D01*
X1973648Y-55348D01*
X1974028Y-55265D01*
X1974408Y-55348D01*
X1974788Y-55681D01*
X1975041Y-56265D01*
X1975105Y-56931D01*
X1975041Y-57598D01*
X1974788Y-58181D01*
X1974408Y-58515D01*
X1974028Y-58598D01*
G01X1980268D02*
Y-55265D01*
G01Y-55848D02*
X1980015Y-55515D01*
X1979635Y-55348D01*
X1979191Y-55265D01*
X1978748Y-55431D01*
X1978368Y-55765D01*
X1978115Y-56265D01*
X1977988Y-56931D01*
X1978115Y-57598D01*
X1978368Y-58098D01*
X1978748Y-58431D01*
X1979191Y-58598D01*
X1979635Y-58515D01*
X1980015Y-58265D01*
X1980268Y-57931D01*
G01X1983341Y-58598D02*
Y-55265D01*
G01Y-55931D02*
X1983658Y-55598D01*
X1983975Y-55348D01*
X1984418Y-55265D01*
X1984735Y-55348D01*
X1985115Y-55598D01*
G01X1990468Y-53598D02*
Y-58598D01*
G01Y-57848D02*
X1990215Y-58265D01*
X1989835Y-58515D01*
X1989391Y-58598D01*
X1988885Y-58431D01*
X1988505Y-58015D01*
X1988251Y-57515D01*
X1988188Y-56931D01*
X1988251Y-56348D01*
X1988505Y-55848D01*
X1988885Y-55431D01*
X1989391Y-55265D01*
X1989835Y-55348D01*
X1990151Y-55515D01*
X1990468Y-55848D01*
G01X1840225Y-20798D02*
Y-15798D01*
X1842631D01*
G01X1841745Y-18215D02*
X1840225D01*
G01X1846528Y-17465D02*
Y-20798D01*
G01Y-16131D02*
X1846401Y-16048D01*
Y-15881D01*
X1846528Y-15798D01*
X1846655Y-15881D01*
Y-16048D01*
X1846528Y-16131D01*
G01X1852768Y-15798D02*
Y-20798D01*
G01Y-20048D02*
X1852515Y-20465D01*
X1852135Y-20715D01*
X1851691Y-20798D01*
X1851185Y-20631D01*
X1850805Y-20215D01*
X1850551Y-19715D01*
X1850488Y-19131D01*
X1850551Y-18548D01*
X1850805Y-18048D01*
X1851185Y-17631D01*
X1851691Y-17465D01*
X1852135Y-17548D01*
X1852451Y-17715D01*
X1852768Y-18048D01*
G01X1855651Y-17465D02*
Y-19798D01*
X1855905Y-20381D01*
X1856285Y-20715D01*
X1856728Y-20798D01*
X1857171Y-20715D01*
X1857551Y-20381D01*
X1857805Y-19798D01*
G01Y-20798D02*
Y-17465D01*
G01X1862841Y-17881D02*
X1862398Y-17548D01*
X1862018Y-17465D01*
X1861511Y-17631D01*
X1861131Y-17965D01*
X1860878Y-18548D01*
X1860815Y-19131D01*
X1860878Y-19715D01*
X1861131Y-20215D01*
X1861511Y-20631D01*
X1862018Y-20798D01*
X1862461Y-20631D01*
X1862841Y-20298D01*
G01X1866928Y-17465D02*
Y-20798D01*
G01Y-16131D02*
X1866801Y-16048D01*
Y-15881D01*
X1866928Y-15798D01*
X1867055Y-15881D01*
Y-16048D01*
X1866928Y-16131D01*
G01X1873168Y-20798D02*
Y-17465D01*
G01Y-18048D02*
X1872915Y-17715D01*
X1872535Y-17548D01*
X1872091Y-17465D01*
X1871648Y-17631D01*
X1871268Y-17965D01*
X1871015Y-18465D01*
X1870888Y-19131D01*
X1871015Y-19798D01*
X1871268Y-20298D01*
X1871648Y-20631D01*
X1872091Y-20798D01*
X1872535Y-20715D01*
X1872915Y-20465D01*
X1873168Y-20131D01*
G01X1877128Y-20798D02*
Y-15798D01*
G01X1885681Y-20798D02*
Y-15798D01*
X1887328Y-19965D01*
X1888975Y-15798D01*
Y-20798D01*
G01X1893568D02*
Y-17465D01*
G01Y-18048D02*
X1893315Y-17715D01*
X1892935Y-17548D01*
X1892491Y-17465D01*
X1892048Y-17631D01*
X1891668Y-17965D01*
X1891415Y-18465D01*
X1891288Y-19131D01*
X1891415Y-19798D01*
X1891668Y-20298D01*
X1892048Y-20631D01*
X1892491Y-20798D01*
X1892935Y-20715D01*
X1893315Y-20465D01*
X1893568Y-20131D01*
G01X1896641Y-20798D02*
Y-17465D01*
G01Y-18131D02*
X1896958Y-17798D01*
X1897275Y-17548D01*
X1897718Y-17465D01*
X1898035Y-17548D01*
X1898415Y-17798D01*
G01X1901551Y-20798D02*
Y-15798D01*
G01X1903578Y-17465D02*
X1901551Y-19381D01*
G01X1902375Y-18631D02*
X1903705Y-20798D01*
G01X1907728Y-20965D02*
X1907601Y-20881D01*
Y-20715D01*
X1907728Y-20631D01*
X1907855Y-20715D01*
Y-20881D01*
X1907728Y-20965D01*
G01Y-18715D02*
X1907601Y-18631D01*
Y-18465D01*
X1907728Y-18381D01*
X1907855Y-18465D01*
Y-18631D01*
X1907728Y-18715D01*
G01X1916535Y-20798D02*
Y-15798D01*
X1917801D01*
X1918308Y-16048D01*
X1918688Y-16381D01*
X1919005Y-16881D01*
X1919258Y-17465D01*
X1919321Y-18298D01*
X1919258Y-19131D01*
X1919005Y-19715D01*
X1918688Y-20215D01*
X1918308Y-20548D01*
X1917801Y-20798D01*
X1916535D01*
G01X1923028Y-17465D02*
Y-20798D01*
G01Y-16131D02*
X1922901Y-16048D01*
Y-15881D01*
X1923028Y-15798D01*
X1923155Y-15881D01*
Y-16048D01*
X1923028Y-16131D01*
G01X1929268Y-20798D02*
Y-17465D01*
G01Y-18048D02*
X1929015Y-17715D01*
X1928635Y-17548D01*
X1928191Y-17465D01*
X1927748Y-17631D01*
X1927368Y-17965D01*
X1927115Y-18465D01*
X1926988Y-19131D01*
X1927115Y-19798D01*
X1927368Y-20298D01*
X1927748Y-20631D01*
X1928191Y-20798D01*
X1928635Y-20715D01*
X1929015Y-20465D01*
X1929268Y-20131D01*
G01X1931328Y-20798D02*
Y-17465D01*
G01Y-18381D02*
X1931518Y-17965D01*
X1931835Y-17631D01*
X1932278Y-17465D01*
X1932721Y-17631D01*
X1933038Y-17965D01*
X1933228Y-18381D01*
Y-20798D01*
G01Y-18381D02*
X1933418Y-17965D01*
X1933735Y-17631D01*
X1934178Y-17465D01*
X1934621Y-17631D01*
X1934938Y-17965D01*
X1935128Y-18465D01*
Y-20798D01*
G01X1937378Y-18548D02*
X1939405D01*
X1939215Y-17965D01*
X1938898Y-17631D01*
X1938455Y-17465D01*
X1938011Y-17548D01*
X1937631Y-17798D01*
X1937378Y-18381D01*
X1937251Y-18881D01*
Y-19381D01*
X1937378Y-19881D01*
X1937695Y-20381D01*
X1938075Y-20715D01*
X1938518Y-20798D01*
X1938961Y-20631D01*
X1939405Y-20131D01*
G01X1943428Y-15798D02*
Y-20798D01*
G01X1942541Y-17465D02*
X1944315D01*
G01X1947578Y-18548D02*
X1949605D01*
X1949415Y-17965D01*
X1949098Y-17631D01*
X1948655Y-17465D01*
X1948211Y-17548D01*
X1947831Y-17798D01*
X1947578Y-18381D01*
X1947451Y-18881D01*
Y-19381D01*
X1947578Y-19881D01*
X1947895Y-20381D01*
X1948275Y-20715D01*
X1948718Y-20798D01*
X1949161Y-20631D01*
X1949605Y-20131D01*
G01X1952741Y-20798D02*
Y-17465D01*
G01Y-18131D02*
X1953058Y-17798D01*
X1953375Y-17548D01*
X1953818Y-17465D01*
X1954135Y-17548D01*
X1954515Y-17798D01*
G01X1963828Y-20798D02*
Y-15798D01*
X1963068Y-16798D01*
G01Y-20798D02*
X1964588D01*
G01X1967028D02*
Y-17465D01*
G01Y-18381D02*
X1967218Y-17965D01*
X1967535Y-17631D01*
X1967978Y-17465D01*
X1968421Y-17631D01*
X1968738Y-17965D01*
X1968928Y-18381D01*
Y-20798D01*
G01Y-18381D02*
X1969118Y-17965D01*
X1969435Y-17631D01*
X1969878Y-17465D01*
X1970321Y-17631D01*
X1970638Y-17965D01*
X1970828Y-18465D01*
Y-20798D01*
G01X1972128D02*
Y-17465D01*
G01Y-18381D02*
X1972318Y-17965D01*
X1972635Y-17631D01*
X1973078Y-17465D01*
X1973521Y-17631D01*
X1973838Y-17965D01*
X1974028Y-18381D01*
Y-20798D01*
G01Y-18381D02*
X1974218Y-17965D01*
X1974535Y-17631D01*
X1974978Y-17465D01*
X1975421Y-17631D01*
X1975738Y-17965D01*
X1975928Y-18465D01*
Y-20798D01*
G01X1985621Y-16215D02*
X1985241Y-15965D01*
X1984798Y-15798D01*
X1984291D01*
X1983721Y-16048D01*
X1983278Y-16465D01*
X1982961Y-16965D01*
X1982708Y-17798D01*
X1982645Y-18548D01*
X1982771Y-19298D01*
X1982961Y-19798D01*
X1983341Y-20298D01*
X1983785Y-20631D01*
X1984228Y-20798D01*
X1984671D01*
X1985115Y-20631D01*
X1985495Y-20381D01*
X1985811Y-20048D01*
G01X1989328Y-20798D02*
X1988948Y-20715D01*
X1988568Y-20381D01*
X1988315Y-19798D01*
X1988188Y-19131D01*
X1988315Y-18465D01*
X1988568Y-17881D01*
X1988948Y-17548D01*
X1989328Y-17465D01*
X1989708Y-17548D01*
X1990088Y-17881D01*
X1990341Y-18465D01*
X1990405Y-19131D01*
X1990341Y-19798D01*
X1990088Y-20381D01*
X1989708Y-20715D01*
X1989328Y-20798D01*
G01X1993288Y-22465D02*
Y-17465D01*
G01Y-18215D02*
X1993605Y-17798D01*
X1993921Y-17548D01*
X1994428Y-17465D01*
X1994871Y-17548D01*
X1995315Y-17965D01*
X1995505Y-18548D01*
X1995568Y-19131D01*
X1995505Y-19715D01*
X1995315Y-20298D01*
X1994935Y-20631D01*
X1994428Y-20798D01*
X1993985Y-20715D01*
X1993541Y-20465D01*
X1993288Y-20131D01*
G01X1998388Y-22465D02*
Y-17465D01*
G01Y-18215D02*
X1998705Y-17798D01*
X1999021Y-17548D01*
X1999528Y-17465D01*
X1999971Y-17548D01*
X2000415Y-17965D01*
X2000605Y-18548D01*
X2000668Y-19131D01*
X2000605Y-19715D01*
X2000415Y-20298D01*
X2000035Y-20631D01*
X1999528Y-20798D01*
X1999085Y-20715D01*
X1998641Y-20465D01*
X1998388Y-20131D01*
G01X2003678Y-18548D02*
X2005705D01*
X2005515Y-17965D01*
X2005198Y-17631D01*
X2004755Y-17465D01*
X2004311Y-17548D01*
X2003931Y-17798D01*
X2003678Y-18381D01*
X2003551Y-18881D01*
Y-19381D01*
X2003678Y-19881D01*
X2003995Y-20381D01*
X2004375Y-20715D01*
X2004818Y-20798D01*
X2005261Y-20631D01*
X2005705Y-20131D01*
G01X2008841Y-20798D02*
Y-17465D01*
G01Y-18131D02*
X2009158Y-17798D01*
X2009475Y-17548D01*
X2009918Y-17465D01*
X2010235Y-17548D01*
X2010615Y-17798D01*
G01X1916535Y-33398D02*
Y-28398D01*
X1917801D01*
X1918308Y-28648D01*
X1918688Y-28981D01*
X1919005Y-29481D01*
X1919258Y-30065D01*
X1919321Y-30898D01*
X1919258Y-31731D01*
X1919005Y-32315D01*
X1918688Y-32815D01*
X1918308Y-33148D01*
X1917801Y-33398D01*
X1916535D01*
G01X1923028Y-30065D02*
Y-33398D01*
G01Y-28731D02*
X1922901Y-28648D01*
Y-28481D01*
X1923028Y-28398D01*
X1923155Y-28481D01*
Y-28648D01*
X1923028Y-28731D01*
G01X1929268Y-33398D02*
Y-30065D01*
G01Y-30648D02*
X1929015Y-30315D01*
X1928635Y-30148D01*
X1928191Y-30065D01*
X1927748Y-30231D01*
X1927368Y-30565D01*
X1927115Y-31065D01*
X1926988Y-31731D01*
X1927115Y-32398D01*
X1927368Y-32898D01*
X1927748Y-33231D01*
X1928191Y-33398D01*
X1928635Y-33315D01*
X1929015Y-33065D01*
X1929268Y-32731D01*
G01X1931328Y-33398D02*
Y-30065D01*
G01Y-30981D02*
X1931518Y-30565D01*
X1931835Y-30231D01*
X1932278Y-30065D01*
X1932721Y-30231D01*
X1933038Y-30565D01*
X1933228Y-30981D01*
Y-33398D01*
G01Y-30981D02*
X1933418Y-30565D01*
X1933735Y-30231D01*
X1934178Y-30065D01*
X1934621Y-30231D01*
X1934938Y-30565D01*
X1935128Y-31065D01*
Y-33398D01*
G01X1937378Y-31148D02*
X1939405D01*
X1939215Y-30565D01*
X1938898Y-30231D01*
X1938455Y-30065D01*
X1938011Y-30148D01*
X1937631Y-30398D01*
X1937378Y-30981D01*
X1937251Y-31481D01*
Y-31981D01*
X1937378Y-32481D01*
X1937695Y-32981D01*
X1938075Y-33315D01*
X1938518Y-33398D01*
X1938961Y-33231D01*
X1939405Y-32731D01*
G01X1943428Y-28398D02*
Y-33398D01*
G01X1942541Y-30065D02*
X1944315D01*
G01X1947578Y-31148D02*
X1949605D01*
X1949415Y-30565D01*
X1949098Y-30231D01*
X1948655Y-30065D01*
X1948211Y-30148D01*
X1947831Y-30398D01*
X1947578Y-30981D01*
X1947451Y-31481D01*
Y-31981D01*
X1947578Y-32481D01*
X1947895Y-32981D01*
X1948275Y-33315D01*
X1948718Y-33398D01*
X1949161Y-33231D01*
X1949605Y-32731D01*
G01X1952741Y-33398D02*
Y-30065D01*
G01Y-30731D02*
X1953058Y-30398D01*
X1953375Y-30148D01*
X1953818Y-30065D01*
X1954135Y-30148D01*
X1954515Y-30398D01*
G01X1962435Y-32398D02*
X1962815Y-32981D01*
X1963321Y-33315D01*
X1963891Y-33398D01*
X1964398Y-33315D01*
X1964905Y-32898D01*
X1965221Y-32398D01*
X1965285Y-31898D01*
X1965158Y-31315D01*
X1964715Y-30898D01*
X1964271Y-30731D01*
X1963701D01*
G01X1964271D02*
X1964651Y-30481D01*
X1964968Y-30065D01*
X1965095Y-29565D01*
X1964968Y-29065D01*
X1964651Y-28648D01*
X1964081Y-28398D01*
X1963511Y-28481D01*
X1962941Y-28815D01*
G01X1967028Y-33398D02*
Y-30065D01*
G01Y-30981D02*
X1967218Y-30565D01*
X1967535Y-30231D01*
X1967978Y-30065D01*
X1968421Y-30231D01*
X1968738Y-30565D01*
X1968928Y-30981D01*
Y-33398D01*
G01Y-30981D02*
X1969118Y-30565D01*
X1969435Y-30231D01*
X1969878Y-30065D01*
X1970321Y-30231D01*
X1970638Y-30565D01*
X1970828Y-31065D01*
Y-33398D01*
G01X1972128D02*
Y-30065D01*
G01Y-30981D02*
X1972318Y-30565D01*
X1972635Y-30231D01*
X1973078Y-30065D01*
X1973521Y-30231D01*
X1973838Y-30565D01*
X1974028Y-30981D01*
Y-33398D01*
G01Y-30981D02*
X1974218Y-30565D01*
X1974535Y-30231D01*
X1974978Y-30065D01*
X1975421Y-30231D01*
X1975738Y-30565D01*
X1975928Y-31065D01*
Y-33398D01*
G01X1982898Y-32731D02*
X1983405Y-33148D01*
X1983975Y-33398D01*
X1984481D01*
X1984988Y-33148D01*
X1985368Y-32731D01*
X1985558Y-32148D01*
X1985431Y-31565D01*
X1985115Y-31065D01*
X1984545Y-30731D01*
X1983785Y-30565D01*
X1983341Y-30231D01*
X1983151Y-29648D01*
X1983278Y-29065D01*
X1983595Y-28648D01*
X1984038Y-28398D01*
X1984481D01*
X1984925Y-28565D01*
X1985305Y-28981D01*
G01X1989328Y-33398D02*
X1988948Y-33315D01*
X1988568Y-32981D01*
X1988315Y-32398D01*
X1988188Y-31731D01*
X1988315Y-31065D01*
X1988568Y-30481D01*
X1988948Y-30148D01*
X1989328Y-30065D01*
X1989708Y-30148D01*
X1990088Y-30481D01*
X1990341Y-31065D01*
X1990405Y-31731D01*
X1990341Y-32398D01*
X1990088Y-32981D01*
X1989708Y-33315D01*
X1989328Y-33398D01*
G01X1994428D02*
Y-28398D01*
G01X2000668D02*
Y-33398D01*
G01Y-32648D02*
X2000415Y-33065D01*
X2000035Y-33315D01*
X1999591Y-33398D01*
X1999085Y-33231D01*
X1998705Y-32815D01*
X1998451Y-32315D01*
X1998388Y-31731D01*
X1998451Y-31148D01*
X1998705Y-30648D01*
X1999085Y-30231D01*
X1999591Y-30065D01*
X2000035Y-30148D01*
X2000351Y-30315D01*
X2000668Y-30648D01*
G01X2003678Y-31148D02*
X2005705D01*
X2005515Y-30565D01*
X2005198Y-30231D01*
X2004755Y-30065D01*
X2004311Y-30148D01*
X2003931Y-30398D01*
X2003678Y-30981D01*
X2003551Y-31481D01*
Y-31981D01*
X2003678Y-32481D01*
X2003995Y-32981D01*
X2004375Y-33315D01*
X2004818Y-33398D01*
X2005261Y-33231D01*
X2005705Y-32731D01*
G01X2008841Y-33398D02*
Y-30065D01*
G01Y-30731D02*
X2009158Y-30398D01*
X2009475Y-30148D01*
X2009918Y-30065D01*
X2010235Y-30148D01*
X2010615Y-30398D01*
G01X2012928Y-33398D02*
Y-30065D01*
G01Y-30981D02*
X2013118Y-30565D01*
X2013435Y-30231D01*
X2013878Y-30065D01*
X2014321Y-30231D01*
X2014638Y-30565D01*
X2014828Y-30981D01*
Y-33398D01*
G01Y-30981D02*
X2015018Y-30565D01*
X2015335Y-30231D01*
X2015778Y-30065D01*
X2016221Y-30231D01*
X2016538Y-30565D01*
X2016728Y-31065D01*
Y-33398D01*
G01X2021068D02*
Y-30065D01*
G01Y-30648D02*
X2020815Y-30315D01*
X2020435Y-30148D01*
X2019991Y-30065D01*
X2019548Y-30231D01*
X2019168Y-30565D01*
X2018915Y-31065D01*
X2018788Y-31731D01*
X2018915Y-32398D01*
X2019168Y-32898D01*
X2019548Y-33231D01*
X2019991Y-33398D01*
X2020435Y-33315D01*
X2020815Y-33065D01*
X2021068Y-32731D01*
G01X2024078Y-32815D02*
X2024395Y-33148D01*
X2024838Y-33398D01*
X2025218D01*
X2025598Y-33231D01*
X2025851Y-32981D01*
X2025978Y-32648D01*
X2025915Y-32148D01*
X2025661Y-31898D01*
X2024521Y-31398D01*
X2024268Y-30815D01*
X2024395Y-30398D01*
X2024648Y-30148D01*
X2025028Y-30065D01*
X2025408Y-30148D01*
X2025788Y-30398D01*
G01X2029051Y-33398D02*
Y-28398D01*
G01X2031078Y-30065D02*
X2029051Y-31981D01*
G01X2029875Y-31231D02*
X2031205Y-33398D01*
G01X1913616Y40894D02*
Y35894D01*
G01X1912159Y40894D02*
X1915073D01*
G01X1918716Y35894D02*
X1918336Y35977D01*
X1917956Y36311D01*
X1917703Y36894D01*
X1917576Y37561D01*
X1917703Y38227D01*
X1917956Y38811D01*
X1918336Y39144D01*
X1918716Y39227D01*
X1919096Y39144D01*
X1919476Y38811D01*
X1919729Y38227D01*
X1919793Y37561D01*
X1919729Y36894D01*
X1919476Y36311D01*
X1919096Y35977D01*
X1918716Y35894D01*
G01X1923816D02*
Y40894D01*
G01X1927966Y38144D02*
X1929993D01*
X1929803Y38727D01*
X1929486Y39061D01*
X1929043Y39227D01*
X1928599Y39144D01*
X1928219Y38894D01*
X1927966Y38311D01*
X1927839Y37811D01*
Y37311D01*
X1927966Y36811D01*
X1928283Y36311D01*
X1928663Y35977D01*
X1929106Y35894D01*
X1929549Y36061D01*
X1929993Y36561D01*
G01X1933129Y35894D02*
Y39227D01*
G01Y38561D02*
X1933446Y38894D01*
X1933763Y39144D01*
X1934206Y39227D01*
X1934523Y39144D01*
X1934903Y38894D01*
G01X1940256Y35894D02*
Y39227D01*
G01Y38644D02*
X1940003Y38977D01*
X1939623Y39144D01*
X1939179Y39227D01*
X1938736Y39061D01*
X1938356Y38727D01*
X1938103Y38227D01*
X1937976Y37561D01*
X1938103Y36894D01*
X1938356Y36394D01*
X1938736Y36061D01*
X1939179Y35894D01*
X1939623Y35977D01*
X1940003Y36227D01*
X1940256Y36561D01*
G01X1943139Y35894D02*
Y39227D01*
G01Y38394D02*
X1943393Y38811D01*
X1943773Y39144D01*
X1944279Y39227D01*
X1944723Y39144D01*
X1945103Y38811D01*
X1945293Y38227D01*
Y35894D01*
G01X1950329Y38811D02*
X1949886Y39144D01*
X1949506Y39227D01*
X1948999Y39061D01*
X1948619Y38727D01*
X1948366Y38144D01*
X1948303Y37561D01*
X1948366Y36977D01*
X1948619Y36477D01*
X1948999Y36061D01*
X1949506Y35894D01*
X1949949Y36061D01*
X1950329Y36394D01*
G01X1953466Y38144D02*
X1955493D01*
X1955303Y38727D01*
X1954986Y39061D01*
X1954543Y39227D01*
X1954099Y39144D01*
X1953719Y38894D01*
X1953466Y38311D01*
X1953339Y37811D01*
Y37311D01*
X1953466Y36811D01*
X1953783Y36311D01*
X1954163Y35977D01*
X1954606Y35894D01*
X1955049Y36061D01*
X1955493Y36561D01*
G01X1963919Y37561D02*
X1965439D01*
G01X1964616Y38644D02*
Y36477D01*
G01X1969716Y40894D02*
X1969209Y40727D01*
X1968829Y40311D01*
X1968576Y39811D01*
X1968386Y39144D01*
X1968323Y38394D01*
X1968386Y37644D01*
X1968576Y36977D01*
X1968829Y36477D01*
X1969209Y36061D01*
X1969716Y35894D01*
X1970223Y36061D01*
X1970603Y36477D01*
X1970856Y36977D01*
X1971046Y37644D01*
X1971109Y38394D01*
X1971046Y39144D01*
X1970856Y39811D01*
X1970603Y40311D01*
X1970223Y40727D01*
X1969716Y40894D01*
G01X1974816Y35727D02*
X1974689Y35811D01*
Y35977D01*
X1974816Y36061D01*
X1974943Y35977D01*
Y35811D01*
X1974816Y35727D01*
G01X1979916Y40894D02*
X1979409Y40727D01*
X1979029Y40311D01*
X1978776Y39811D01*
X1978586Y39144D01*
X1978523Y38394D01*
X1978586Y37644D01*
X1978776Y36977D01*
X1979029Y36477D01*
X1979409Y36061D01*
X1979916Y35894D01*
X1980423Y36061D01*
X1980803Y36477D01*
X1981056Y36977D01*
X1981246Y37644D01*
X1981309Y38394D01*
X1981246Y39144D01*
X1981056Y39811D01*
X1980803Y40311D01*
X1980423Y40727D01*
X1979916Y40894D01*
G01X1983623Y36644D02*
X1984003Y36227D01*
X1984446Y35977D01*
X1985016Y35894D01*
X1985586Y36061D01*
X1986029Y36394D01*
X1986346Y36977D01*
X1986409Y37644D01*
X1986283Y38311D01*
X1985966Y38727D01*
X1985523Y39061D01*
X1985079Y39144D01*
X1984636Y39061D01*
X1984066Y38727D01*
X1984256Y40894D01*
X1985966D01*
G01X1990116D02*
X1989609Y40727D01*
X1989229Y40311D01*
X1988976Y39811D01*
X1988786Y39144D01*
X1988723Y38394D01*
X1988786Y37644D01*
X1988976Y36977D01*
X1989229Y36477D01*
X1989609Y36061D01*
X1990116Y35894D01*
X1990623Y36061D01*
X1991003Y36477D01*
X1991256Y36977D01*
X1991446Y37644D01*
X1991509Y38394D01*
X1991446Y39144D01*
X1991256Y39811D01*
X1991003Y40311D01*
X1990623Y40727D01*
X1990116Y40894D01*
G01X1995216Y35894D02*
X1995659Y35977D01*
X1996166Y36227D01*
X1996483Y36644D01*
X1996609Y37227D01*
X1996483Y37811D01*
X1996103Y38311D01*
X1995533Y38561D01*
X1994899D01*
X1994519Y38727D01*
X1994203Y39144D01*
X1994076Y39727D01*
X1994266Y40311D01*
X1994709Y40727D01*
X1995216Y40894D01*
X1995723Y40727D01*
X1996166Y40311D01*
X1996356Y39727D01*
X1996229Y39144D01*
X1995913Y38727D01*
X1995533Y38561D01*
X1994899D01*
X1994329Y38311D01*
X1993949Y37811D01*
X1993823Y37227D01*
X1993949Y36644D01*
X1994266Y36227D01*
X1994773Y35977D01*
X1995216Y35894D01*
G01X1998416D02*
Y39227D01*
G01Y38311D02*
X1998606Y38727D01*
X1998923Y39061D01*
X1999366Y39227D01*
X1999809Y39061D01*
X2000126Y38727D01*
X2000316Y38311D01*
Y35894D01*
G01Y38311D02*
X2000506Y38727D01*
X2000823Y39061D01*
X2001266Y39227D01*
X2001709Y39061D01*
X2002026Y38727D01*
X2002216Y38227D01*
Y35894D01*
G01X2003516D02*
Y39227D01*
G01Y38311D02*
X2003706Y38727D01*
X2004023Y39061D01*
X2004466Y39227D01*
X2004909Y39061D01*
X2005226Y38727D01*
X2005416Y38311D01*
Y35894D01*
G01Y38311D02*
X2005606Y38727D01*
X2005923Y39061D01*
X2006366Y39227D01*
X2006809Y39061D01*
X2007126Y38727D01*
X2007316Y38227D01*
Y35894D01*
G01X2009376Y35727D02*
X2011656Y40894D01*
G01X2014793Y37561D02*
X2016439D01*
G01X2020716Y40894D02*
X2020209Y40727D01*
X2019829Y40311D01*
X2019576Y39811D01*
X2019386Y39144D01*
X2019323Y38394D01*
X2019386Y37644D01*
X2019576Y36977D01*
X2019829Y36477D01*
X2020209Y36061D01*
X2020716Y35894D01*
X2021223Y36061D01*
X2021603Y36477D01*
X2021856Y36977D01*
X2022046Y37644D01*
X2022109Y38394D01*
X2022046Y39144D01*
X2021856Y39811D01*
X2021603Y40311D01*
X2021223Y40727D01*
X2020716Y40894D01*
G01X2025816Y35727D02*
X2025689Y35811D01*
Y35977D01*
X2025816Y36061D01*
X2025943Y35977D01*
Y35811D01*
X2025816Y35727D01*
G01X2030916Y40894D02*
X2030409Y40727D01*
X2030029Y40311D01*
X2029776Y39811D01*
X2029586Y39144D01*
X2029523Y38394D01*
X2029586Y37644D01*
X2029776Y36977D01*
X2030029Y36477D01*
X2030409Y36061D01*
X2030916Y35894D01*
X2031423Y36061D01*
X2031803Y36477D01*
X2032056Y36977D01*
X2032246Y37644D01*
X2032309Y38394D01*
X2032246Y39144D01*
X2032056Y39811D01*
X2031803Y40311D01*
X2031423Y40727D01*
X2030916Y40894D01*
G01X2034813Y40061D02*
X2035193Y40561D01*
X2035636Y40811D01*
X2036143Y40894D01*
X2036776Y40727D01*
X2037219Y40311D01*
X2037346Y39811D01*
X2037283Y39311D01*
X2037029Y38894D01*
X2035763Y38061D01*
X2035193Y37477D01*
X2034813Y36644D01*
X2034686Y35894D01*
X2037346D01*
G01X2039723Y36644D02*
X2040103Y36227D01*
X2040546Y35977D01*
X2041116Y35894D01*
X2041686Y36061D01*
X2042129Y36394D01*
X2042446Y36977D01*
X2042509Y37644D01*
X2042383Y38311D01*
X2042066Y38727D01*
X2041623Y39061D01*
X2041179Y39144D01*
X2040736Y39061D01*
X2040166Y38727D01*
X2040356Y40894D01*
X2042066D01*
G01X2046976Y35894D02*
Y40894D01*
X2044633Y37311D01*
X2047799D01*
G01X2049416Y35894D02*
Y39227D01*
G01Y38311D02*
X2049606Y38727D01*
X2049923Y39061D01*
X2050366Y39227D01*
X2050809Y39061D01*
X2051126Y38727D01*
X2051316Y38311D01*
Y35894D01*
G01Y38311D02*
X2051506Y38727D01*
X2051823Y39061D01*
X2052266Y39227D01*
X2052709Y39061D01*
X2053026Y38727D01*
X2053216Y38227D01*
Y35894D01*
G01X2054516D02*
Y39227D01*
G01Y38311D02*
X2054706Y38727D01*
X2055023Y39061D01*
X2055466Y39227D01*
X2055909Y39061D01*
X2056226Y38727D01*
X2056416Y38311D01*
Y35894D01*
G01Y38311D02*
X2056606Y38727D01*
X2056923Y39061D01*
X2057366Y39227D01*
X2057809Y39061D01*
X2058126Y38727D01*
X2058316Y38227D01*
Y35894D01*
G01X1842216Y53494D02*
Y48494D01*
G01X1840759Y53494D02*
X1843673D01*
G01X1847316Y48494D02*
X1846936Y48577D01*
X1846556Y48911D01*
X1846303Y49494D01*
X1846176Y50161D01*
X1846303Y50827D01*
X1846556Y51411D01*
X1846936Y51744D01*
X1847316Y51827D01*
X1847696Y51744D01*
X1848076Y51411D01*
X1848329Y50827D01*
X1848393Y50161D01*
X1848329Y49494D01*
X1848076Y48911D01*
X1847696Y48577D01*
X1847316Y48494D01*
G01X1852416D02*
X1852036Y48577D01*
X1851656Y48911D01*
X1851403Y49494D01*
X1851276Y50161D01*
X1851403Y50827D01*
X1851656Y51411D01*
X1852036Y51744D01*
X1852416Y51827D01*
X1852796Y51744D01*
X1853176Y51411D01*
X1853429Y50827D01*
X1853493Y50161D01*
X1853429Y49494D01*
X1853176Y48911D01*
X1852796Y48577D01*
X1852416Y48494D01*
G01X1857516D02*
Y53494D01*
G01X1862616Y51827D02*
Y48494D01*
G01Y53161D02*
X1862489Y53244D01*
Y53411D01*
X1862616Y53494D01*
X1862743Y53411D01*
Y53244D01*
X1862616Y53161D01*
G01X1866639Y48494D02*
Y51827D01*
G01Y50994D02*
X1866893Y51411D01*
X1867273Y51744D01*
X1867779Y51827D01*
X1868223Y51744D01*
X1868603Y51411D01*
X1868793Y50827D01*
Y48494D01*
G01X1871929Y47244D02*
X1872373Y46911D01*
X1872879Y46827D01*
X1873323Y46911D01*
X1873703Y47327D01*
X1873956Y47911D01*
Y51827D01*
G01Y51161D02*
X1873703Y51494D01*
X1873323Y51744D01*
X1872879Y51827D01*
X1872373Y51661D01*
X1872056Y51327D01*
X1871803Y50744D01*
X1871676Y50161D01*
X1871739Y49661D01*
X1871993Y49077D01*
X1872373Y48661D01*
X1872879Y48494D01*
X1873259Y48577D01*
X1873703Y48911D01*
X1873956Y49244D01*
G01X1881686Y48494D02*
Y53494D01*
G01X1884346D02*
Y48494D01*
G01Y50994D02*
X1881686D01*
G01X1888116Y48494D02*
X1887736Y48577D01*
X1887356Y48911D01*
X1887103Y49494D01*
X1886976Y50161D01*
X1887103Y50827D01*
X1887356Y51411D01*
X1887736Y51744D01*
X1888116Y51827D01*
X1888496Y51744D01*
X1888876Y51411D01*
X1889129Y50827D01*
X1889193Y50161D01*
X1889129Y49494D01*
X1888876Y48911D01*
X1888496Y48577D01*
X1888116Y48494D01*
G01X1893216D02*
Y53494D01*
G01X1897366Y50744D02*
X1899393D01*
X1899203Y51327D01*
X1898886Y51661D01*
X1898443Y51827D01*
X1897999Y51744D01*
X1897619Y51494D01*
X1897366Y50911D01*
X1897239Y50411D01*
Y49911D01*
X1897366Y49411D01*
X1897683Y48911D01*
X1898063Y48577D01*
X1898506Y48494D01*
X1898949Y48661D01*
X1899393Y49161D01*
G01X1903416Y48327D02*
X1903289Y48411D01*
Y48577D01*
X1903416Y48661D01*
X1903543Y48577D01*
Y48411D01*
X1903416Y48327D01*
G01Y50577D02*
X1903289Y50661D01*
Y50827D01*
X1903416Y50911D01*
X1903543Y50827D01*
Y50661D01*
X1903416Y50577D01*
G01X1912223Y48494D02*
Y53494D01*
X1913489D01*
X1913996Y53244D01*
X1914376Y52911D01*
X1914693Y52411D01*
X1914946Y51827D01*
X1915009Y50994D01*
X1914946Y50161D01*
X1914693Y49577D01*
X1914376Y49077D01*
X1913996Y48744D01*
X1913489Y48494D01*
X1912223D01*
G01X1918716Y51827D02*
Y48494D01*
G01Y53161D02*
X1918589Y53244D01*
Y53411D01*
X1918716Y53494D01*
X1918843Y53411D01*
Y53244D01*
X1918716Y53161D01*
G01X1924956Y48494D02*
Y51827D01*
G01Y51244D02*
X1924703Y51577D01*
X1924323Y51744D01*
X1923879Y51827D01*
X1923436Y51661D01*
X1923056Y51327D01*
X1922803Y50827D01*
X1922676Y50161D01*
X1922803Y49494D01*
X1923056Y48994D01*
X1923436Y48661D01*
X1923879Y48494D01*
X1924323Y48577D01*
X1924703Y48827D01*
X1924956Y49161D01*
G01X1927016Y48494D02*
Y51827D01*
G01Y50911D02*
X1927206Y51327D01*
X1927523Y51661D01*
X1927966Y51827D01*
X1928409Y51661D01*
X1928726Y51327D01*
X1928916Y50911D01*
Y48494D01*
G01Y50911D02*
X1929106Y51327D01*
X1929423Y51661D01*
X1929866Y51827D01*
X1930309Y51661D01*
X1930626Y51327D01*
X1930816Y50827D01*
Y48494D01*
G01X1933066Y50744D02*
X1935093D01*
X1934903Y51327D01*
X1934586Y51661D01*
X1934143Y51827D01*
X1933699Y51744D01*
X1933319Y51494D01*
X1933066Y50911D01*
X1932939Y50411D01*
Y49911D01*
X1933066Y49411D01*
X1933383Y48911D01*
X1933763Y48577D01*
X1934206Y48494D01*
X1934649Y48661D01*
X1935093Y49161D01*
G01X1939116Y53494D02*
Y48494D01*
G01X1938229Y51827D02*
X1940003D01*
G01X1943266Y50744D02*
X1945293D01*
X1945103Y51327D01*
X1944786Y51661D01*
X1944343Y51827D01*
X1943899Y51744D01*
X1943519Y51494D01*
X1943266Y50911D01*
X1943139Y50411D01*
Y49911D01*
X1943266Y49411D01*
X1943583Y48911D01*
X1943963Y48577D01*
X1944406Y48494D01*
X1944849Y48661D01*
X1945293Y49161D01*
G01X1948429Y48494D02*
Y51827D01*
G01Y51161D02*
X1948746Y51494D01*
X1949063Y51744D01*
X1949506Y51827D01*
X1949823Y51744D01*
X1950203Y51494D01*
G01X1960276Y48494D02*
Y53494D01*
X1957933Y49911D01*
X1961099D01*
G01X1962716Y48494D02*
Y51827D01*
G01Y50911D02*
X1962906Y51327D01*
X1963223Y51661D01*
X1963666Y51827D01*
X1964109Y51661D01*
X1964426Y51327D01*
X1964616Y50911D01*
Y48494D01*
G01Y50911D02*
X1964806Y51327D01*
X1965123Y51661D01*
X1965566Y51827D01*
X1966009Y51661D01*
X1966326Y51327D01*
X1966516Y50827D01*
Y48494D01*
G01X1967816D02*
Y51827D01*
G01Y50911D02*
X1968006Y51327D01*
X1968323Y51661D01*
X1968766Y51827D01*
X1969209Y51661D01*
X1969526Y51327D01*
X1969716Y50911D01*
Y48494D01*
G01Y50911D02*
X1969906Y51327D01*
X1970223Y51661D01*
X1970666Y51827D01*
X1971109Y51661D01*
X1971426Y51327D01*
X1971616Y50827D01*
Y48494D01*
G01X1978459D02*
Y53494D01*
X1981373Y48494D01*
Y53494D01*
G01X1983749Y48494D02*
Y53494D01*
X1985269D01*
X1985776Y53244D01*
X1986156Y52661D01*
X1986283Y51994D01*
X1986156Y51327D01*
X1985839Y50827D01*
X1985269Y50577D01*
X1983749D01*
G01X1990116Y53494D02*
Y48494D01*
G01X1988659Y53494D02*
X1991573D01*
G01X1993886Y48494D02*
Y53494D01*
G01X1996546D02*
Y48494D01*
G01Y50994D02*
X1993886D01*
G01X1860972Y-162158D02*
X1860472Y-161778D01*
X1860222Y-161335D01*
X1860139Y-160828D01*
X1860306Y-160195D01*
X1860722Y-159752D01*
X1861222Y-159625D01*
X1861722Y-159688D01*
X1862139Y-159942D01*
X1862972Y-161208D01*
X1863556Y-161778D01*
X1864389Y-162158D01*
X1865139Y-162285D01*
Y-159625D01*
G01X1866654Y-151113D02*
X1867639Y-157018D01*
X1868623Y-151113D01*
X1866654D01*
G01X1867639Y-160955D02*
Y-157018D01*
G01X1868623Y-170798D02*
X1867639Y-164892D01*
X1866654Y-170798D01*
X1868623D01*
G01X1867639Y-160955D02*
Y-164892D01*
G01X1882206D02*
X1867245D01*
G01X1882206Y-157018D02*
X1867245D01*
G01X1869469Y-84278D02*
X1882932Y-105819D01*
G01X1873434Y-88764D02*
X1869469Y-84278D01*
X1871765Y-89807D01*
X1873434Y-88764D01*
G01X1890867Y-183593D02*
X1896772Y-182609D01*
X1890867Y-181624D01*
Y-183593D01*
G01X1882058Y-99703D02*
X1886298Y-97053D01*
X1885047Y-96939D01*
G01X1881655Y-99059D02*
X1882461Y-100348D01*
G01X1885662Y-93677D02*
X1876652Y-93412D01*
G01X1883657Y-93544D02*
G03I-2500J0D01*
G01X1875018Y-81723D02*
X1905347Y-74724D01*
G01X1880551Y-79436D02*
X1875018Y-81723D01*
X1880994Y-81354D01*
X1880551Y-79436D01*
G01X1894756Y-68189D02*
X1891571Y-76620D01*
G01X1895664Y-72405D02*
G03I-2501J0D01*
G01X1876348Y16422D02*
X1912685Y24496D01*
G01X1881900Y18663D02*
X1876348Y16422D01*
X1882327Y16743D01*
X1881900Y18663D01*
G01X1901679Y-179109D02*
X1902059Y-179692D01*
X1902565Y-180026D01*
X1903135Y-180109D01*
X1903642Y-180026D01*
X1904149Y-179609D01*
X1904465Y-179109D01*
X1904529Y-178609D01*
X1904402Y-178026D01*
X1903959Y-177609D01*
X1903515Y-177442D01*
X1902945D01*
G01X1903515D02*
X1903895Y-177192D01*
X1904212Y-176776D01*
X1904339Y-176276D01*
X1904212Y-175776D01*
X1903895Y-175359D01*
X1903325Y-175109D01*
X1902755Y-175192D01*
X1902185Y-175526D01*
G01X1914489Y-181624D02*
X1908583Y-182609D01*
X1914489Y-183593D01*
Y-181624D01*
G01X1903072Y-182609D02*
X1908583D01*
G01X1903072D02*
X1896772D01*
G01X1908583Y-163317D02*
Y-183002D01*
G01X1896772Y-163317D02*
Y-183002D01*
G01X1897697Y-72898D02*
X1898198Y-73381D01*
X1898767Y-73592D01*
X1899341Y-73545D01*
X1899816Y-73349D01*
X1900216Y-72830D01*
X1900412Y-72271D01*
X1900361Y-71770D01*
X1900107Y-71230D01*
X1899581Y-70924D01*
X1899112Y-70861D01*
X1898556Y-70989D01*
G01X1899112Y-70861D02*
X1899426Y-70532D01*
X1899641Y-70055D01*
X1899652Y-69539D01*
X1899416Y-69080D01*
X1899014Y-68745D01*
X1898402Y-68630D01*
X1897865Y-68839D01*
X1897385Y-69292D01*
G01X1907370Y25876D02*
X1906285Y30757D01*
X1904775Y26751D01*
X1907866Y27438D01*
G01X1902148Y31118D02*
X1898894Y22712D01*
G01X1903021Y26915D02*
G03I-2500J0D01*
G01X-471400Y-391900D02*
Y1528800D01*
X2244200D01*
Y-391900D01*
X-471400D01*
G01X-43307Y-198031D02*
G03I-7874J0D01*
G01X-45276Y700392D02*
G03I-5905J0D01*
G01X-43307Y727951D02*
G03I-7874J0D01*
G01X455917Y-335560D02*
X456544Y-336085D01*
X457249Y-336400D01*
X457875D01*
X458502Y-336085D01*
X458972Y-335560D01*
X459207Y-334825D01*
X459050Y-334090D01*
X458659Y-333460D01*
X457954Y-333040D01*
X457014Y-332830D01*
X456465Y-332410D01*
X456230Y-331675D01*
X456387Y-330940D01*
X456779Y-330415D01*
X457327Y-330100D01*
X457875D01*
X458424Y-330310D01*
X458894Y-330835D01*
G01X462217Y-336400D02*
Y-330100D01*
G01X465507D02*
Y-336400D01*
G01Y-333250D02*
X462217D01*
G01X469222Y-330100D02*
X471102D01*
G01X470162D02*
Y-336400D01*
G01X469222D02*
X471102D01*
G01X478029D02*
X474895D01*
Y-330100D01*
X478029D01*
G01X476775Y-333145D02*
X474895D01*
G01X480960Y-336400D02*
Y-330100D01*
X484564Y-336400D01*
Y-330100D01*
G01X488905Y-337555D02*
X489219Y-336190D01*
G01X495362Y-330100D02*
Y-336400D01*
G01X493560Y-330100D02*
X497164D01*
G01X499704Y-336400D02*
X501662Y-330100D01*
X503620Y-336400D01*
G01X502915Y-334195D02*
X500409D01*
G01X507022Y-330100D02*
X508902D01*
G01X507962D02*
Y-336400D01*
G01X507022D02*
X508902D01*
G01X511912Y-330100D02*
X513009Y-336400D01*
X514262Y-330100D01*
X515515Y-336400D01*
X516612Y-330100D01*
G01X518604Y-336400D02*
X520562Y-330100D01*
X522520Y-336400D01*
G01X521815Y-334195D02*
X519309D01*
G01X525060Y-336400D02*
Y-330100D01*
X528664Y-336400D01*
Y-330100D01*
G01X537895Y-336400D02*
Y-330100D01*
X539854D01*
X540480Y-330415D01*
X540872Y-330835D01*
X541029Y-331675D01*
X540872Y-332515D01*
X540402Y-333040D01*
X539854Y-333355D01*
X537895D01*
G01X539854D02*
X541029Y-336400D01*
G01X545762Y-336610D02*
X545605Y-336505D01*
Y-336295D01*
X545762Y-336190D01*
X545919Y-336295D01*
Y-336505D01*
X545762Y-336610D01*
G01X552062Y-336400D02*
X551435Y-336295D01*
X550887Y-335875D01*
X550417Y-335245D01*
X550104Y-334510D01*
X549947Y-333670D01*
Y-332830D01*
X550104Y-331990D01*
X550417Y-331255D01*
X550887Y-330625D01*
X551435Y-330205D01*
X552062Y-330100D01*
X552689Y-330205D01*
X553237Y-330625D01*
X553707Y-331255D01*
X554020Y-331990D01*
X554177Y-332830D01*
Y-333670D01*
X554020Y-334510D01*
X553707Y-335245D01*
X553237Y-335875D01*
X552689Y-336295D01*
X552062Y-336400D01*
G01X558362Y-336610D02*
X558205Y-336505D01*
Y-336295D01*
X558362Y-336190D01*
X558519Y-336295D01*
Y-336505D01*
X558362Y-336610D01*
G01X566385Y-330625D02*
X565915Y-330310D01*
X565367Y-330100D01*
X564740D01*
X564035Y-330415D01*
X563487Y-330940D01*
X563095Y-331570D01*
X562782Y-332620D01*
X562704Y-333565D01*
X562860Y-334510D01*
X563095Y-335140D01*
X563565Y-335770D01*
X564114Y-336190D01*
X564662Y-336400D01*
X565210D01*
X565759Y-336190D01*
X566229Y-335875D01*
X566620Y-335455D01*
G01X570962Y-336610D02*
X570805Y-336505D01*
Y-336295D01*
X570962Y-336190D01*
X571119Y-336295D01*
Y-336505D01*
X570962Y-336610D01*
G01X455839Y-326400D02*
Y-320100D01*
G01X458815D02*
X455839Y-323985D01*
G01X459285Y-326400D02*
X457170Y-322200D01*
G01X462139Y-320100D02*
Y-324615D01*
X462452Y-325560D01*
X463079Y-326190D01*
X463862Y-326400D01*
X464645Y-326190D01*
X465272Y-325560D01*
X465585Y-324615D01*
Y-320100D01*
G01X471729Y-326400D02*
X468595D01*
Y-320100D01*
X471729D01*
G01X470475Y-323145D02*
X468595D01*
G01X475522Y-320100D02*
X477402D01*
G01X476462D02*
Y-326400D01*
G01X475522D02*
X477402D01*
G01X487417Y-325560D02*
X488044Y-326085D01*
X488749Y-326400D01*
X489375D01*
X490002Y-326085D01*
X490472Y-325560D01*
X490707Y-324825D01*
X490550Y-324090D01*
X490159Y-323460D01*
X489454Y-323040D01*
X488514Y-322830D01*
X487965Y-322410D01*
X487730Y-321675D01*
X487887Y-320940D01*
X488279Y-320415D01*
X488827Y-320100D01*
X489375D01*
X489924Y-320310D01*
X490394Y-320835D01*
G01X493717Y-326400D02*
Y-320100D01*
G01X497007D02*
Y-326400D01*
G01Y-323250D02*
X493717D01*
G01X499704Y-326400D02*
X501662Y-320100D01*
X503620Y-326400D01*
G01X502915Y-324195D02*
X500409D01*
G01X506160Y-326400D02*
Y-320100D01*
X509764Y-326400D01*
Y-320100D01*
G01X518917Y-326400D02*
Y-320100D01*
G01X522207D02*
Y-326400D01*
G01Y-323250D02*
X518917D01*
G01X525217Y-325560D02*
X525844Y-326085D01*
X526549Y-326400D01*
X527175D01*
X527802Y-326085D01*
X528272Y-325560D01*
X528507Y-324825D01*
X528350Y-324090D01*
X527959Y-323460D01*
X527254Y-323040D01*
X526314Y-322830D01*
X525765Y-322410D01*
X525530Y-321675D01*
X525687Y-320940D01*
X526079Y-320415D01*
X526627Y-320100D01*
X527175D01*
X527724Y-320310D01*
X528194Y-320835D01*
G01X532222Y-320100D02*
X534102D01*
G01X533162D02*
Y-326400D01*
G01X532222D02*
X534102D01*
G01X537504D02*
X539462Y-320100D01*
X541420Y-326400D01*
G01X540715Y-324195D02*
X538209D01*
G01X543960Y-326400D02*
Y-320100D01*
X547564Y-326400D01*
Y-320100D01*
G01X552532Y-323250D02*
X554099D01*
Y-325140D01*
X553629Y-325770D01*
X553080Y-326190D01*
X552297Y-326400D01*
X551514Y-326190D01*
X550965Y-325770D01*
X550495Y-325140D01*
X550182Y-324405D01*
X550025Y-323565D01*
Y-322830D01*
X550182Y-322200D01*
X550495Y-321465D01*
X550965Y-320835D01*
X551435Y-320415D01*
X552062Y-320100D01*
X552610D01*
X553237Y-320310D01*
X553707Y-320730D01*
G01X558205Y-327555D02*
X558519Y-326190D01*
G01X564662Y-320100D02*
Y-326400D01*
G01X562860Y-320100D02*
X566464D01*
G01X569004Y-326400D02*
X570962Y-320100D01*
X572920Y-326400D01*
G01X572215Y-324195D02*
X569709D01*
G01X577262Y-326400D02*
X576635Y-326295D01*
X576087Y-325875D01*
X575617Y-325245D01*
X575304Y-324510D01*
X575147Y-323670D01*
Y-322830D01*
X575304Y-321990D01*
X575617Y-321255D01*
X576087Y-320625D01*
X576635Y-320205D01*
X577262Y-320100D01*
X577889Y-320205D01*
X578437Y-320625D01*
X578907Y-321255D01*
X579220Y-321990D01*
X579377Y-322830D01*
Y-323670D01*
X579220Y-324510D01*
X578907Y-325245D01*
X578437Y-325875D01*
X577889Y-326295D01*
X577262Y-326400D01*
G01X589862D02*
Y-323565D01*
X588295Y-320100D01*
G01X591429D02*
X589862Y-323565D01*
G01X594439Y-320100D02*
Y-324615D01*
X594752Y-325560D01*
X595379Y-326190D01*
X596162Y-326400D01*
X596945Y-326190D01*
X597572Y-325560D01*
X597885Y-324615D01*
Y-320100D01*
G01X600504Y-326400D02*
X602462Y-320100D01*
X604420Y-326400D01*
G01X603715Y-324195D02*
X601209D01*
G01X606960Y-326400D02*
Y-320100D01*
X610564Y-326400D01*
Y-320100D01*
G01X455760Y-316400D02*
Y-310100D01*
X459364Y-316400D01*
Y-310100D01*
G01X463862Y-316400D02*
X463235Y-316295D01*
X462687Y-315875D01*
X462217Y-315245D01*
X461904Y-314510D01*
X461747Y-313670D01*
Y-312830D01*
X461904Y-311990D01*
X462217Y-311255D01*
X462687Y-310625D01*
X463235Y-310205D01*
X463862Y-310100D01*
X464489Y-310205D01*
X465037Y-310625D01*
X465507Y-311255D01*
X465820Y-311990D01*
X465977Y-312830D01*
Y-313670D01*
X465820Y-314510D01*
X465507Y-315245D01*
X465037Y-315875D01*
X464489Y-316295D01*
X463862Y-316400D01*
G01X470162Y-316610D02*
X470005Y-316505D01*
Y-316295D01*
X470162Y-316190D01*
X470319Y-316295D01*
Y-316505D01*
X470162Y-316610D01*
G01X476462Y-316400D02*
Y-310100D01*
X475522Y-311360D01*
G01Y-316400D02*
X477402D01*
G01X482762D02*
X483310Y-316295D01*
X483937Y-315980D01*
X484329Y-315455D01*
X484485Y-314720D01*
X484329Y-313985D01*
X483859Y-313355D01*
X483154Y-313040D01*
X482370D01*
X481900Y-312830D01*
X481509Y-312305D01*
X481352Y-311570D01*
X481587Y-310835D01*
X482135Y-310310D01*
X482762Y-310100D01*
X483389Y-310310D01*
X483937Y-310835D01*
X484172Y-311570D01*
X484015Y-312305D01*
X483624Y-312830D01*
X483154Y-313040D01*
X482370D01*
X481665Y-313355D01*
X481195Y-313985D01*
X481039Y-314720D01*
X481195Y-315455D01*
X481587Y-315980D01*
X482214Y-316295D01*
X482762Y-316400D01*
G01X489062D02*
X489610Y-316295D01*
X490237Y-315980D01*
X490629Y-315455D01*
X490785Y-314720D01*
X490629Y-313985D01*
X490159Y-313355D01*
X489454Y-313040D01*
X488670D01*
X488200Y-312830D01*
X487809Y-312305D01*
X487652Y-311570D01*
X487887Y-310835D01*
X488435Y-310310D01*
X489062Y-310100D01*
X489689Y-310310D01*
X490237Y-310835D01*
X490472Y-311570D01*
X490315Y-312305D01*
X489924Y-312830D01*
X489454Y-313040D01*
X488670D01*
X487965Y-313355D01*
X487495Y-313985D01*
X487339Y-314720D01*
X487495Y-315455D01*
X487887Y-315980D01*
X488514Y-316295D01*
X489062Y-316400D01*
G01X495205Y-317555D02*
X495519Y-316190D01*
G01X499312Y-310100D02*
X500409Y-316400D01*
X501662Y-310100D01*
X502915Y-316400D01*
X504012Y-310100D01*
G01X509529Y-316400D02*
X506395D01*
Y-310100D01*
X509529D01*
G01X508275Y-313145D02*
X506395D01*
G01X512460Y-316400D02*
Y-310100D01*
X516064Y-316400D01*
Y-310100D01*
G01X525217Y-316400D02*
Y-310100D01*
G01X528507D02*
Y-316400D01*
G01Y-313250D02*
X525217D01*
G01X530812Y-310100D02*
X531909Y-316400D01*
X533162Y-310100D01*
X534415Y-316400D01*
X535512Y-310100D01*
G01X537504Y-316400D02*
X539462Y-310100D01*
X541420Y-316400D01*
G01X540715Y-314195D02*
X538209D01*
G01X550574Y-311150D02*
X551044Y-310520D01*
X551592Y-310205D01*
X552219Y-310100D01*
X553002Y-310310D01*
X553550Y-310835D01*
X553707Y-311465D01*
X553629Y-312095D01*
X553315Y-312620D01*
X551749Y-313670D01*
X551044Y-314405D01*
X550574Y-315455D01*
X550417Y-316400D01*
X553707D01*
G01X556560D02*
Y-310100D01*
X560164Y-316400D01*
Y-310100D01*
G01X562939Y-316400D02*
Y-310100D01*
X564505D01*
X565132Y-310415D01*
X565602Y-310835D01*
X565994Y-311465D01*
X566307Y-312200D01*
X566385Y-313250D01*
X566307Y-314300D01*
X565994Y-315035D01*
X565602Y-315665D01*
X565132Y-316085D01*
X564505Y-316400D01*
X562939D01*
G01X575695D02*
Y-310100D01*
X577654D01*
X578280Y-310415D01*
X578672Y-310835D01*
X578829Y-311675D01*
X578672Y-312515D01*
X578202Y-313040D01*
X577654Y-313355D01*
X575695D01*
G01X577654D02*
X578829Y-316400D01*
G01X581839D02*
Y-310100D01*
X583405D01*
X584032Y-310415D01*
X584502Y-310835D01*
X584894Y-311465D01*
X585207Y-312200D01*
X585285Y-313250D01*
X585207Y-314300D01*
X584894Y-315035D01*
X584502Y-315665D01*
X584032Y-316085D01*
X583405Y-316400D01*
X581839D01*
G01X589862Y-316610D02*
X589705Y-316505D01*
Y-316295D01*
X589862Y-316190D01*
X590019Y-316295D01*
Y-316505D01*
X589862Y-316610D01*
G01X479862Y-303700D02*
X477342Y-303283D01*
X475137Y-301617D01*
X473247Y-299117D01*
X471987Y-296200D01*
X471357Y-292867D01*
Y-289533D01*
X471987Y-286200D01*
X473247Y-283283D01*
X475137Y-280784D01*
X477342Y-279117D01*
X479862Y-278700D01*
X482382Y-279117D01*
X484587Y-280784D01*
X486477Y-283283D01*
X487737Y-286200D01*
X488367Y-289533D01*
Y-292867D01*
X487737Y-296200D01*
X486477Y-299117D01*
X484587Y-301617D01*
X482382Y-303283D01*
X479862Y-303700D01*
G01X482382Y-297033D02*
X486162Y-303700D01*
G01X499707Y-287034D02*
Y-298700D01*
X500967Y-301617D01*
X502857Y-303283D01*
X505062Y-303700D01*
X507267Y-303283D01*
X509157Y-301617D01*
X510417Y-298700D01*
G01Y-303700D02*
Y-287034D01*
G01X535932Y-303700D02*
Y-287034D01*
G01Y-289950D02*
X534672Y-288284D01*
X532782Y-287450D01*
X530577Y-287034D01*
X528372Y-287867D01*
X526482Y-289533D01*
X525222Y-292034D01*
X524592Y-295367D01*
X525222Y-298700D01*
X526482Y-301201D01*
X528372Y-302867D01*
X530577Y-303700D01*
X532782Y-303283D01*
X534672Y-302034D01*
X535932Y-300367D01*
G01X550107Y-303700D02*
Y-287034D01*
G01Y-291200D02*
X551367Y-289117D01*
X553257Y-287450D01*
X555777Y-287034D01*
X557982Y-287450D01*
X559872Y-289117D01*
X560817Y-292034D01*
Y-303700D01*
G01X580662Y-278700D02*
Y-303700D01*
G01X576252Y-287034D02*
X585072D01*
G01X611532Y-303700D02*
Y-287034D01*
G01Y-289950D02*
X610272Y-288284D01*
X608382Y-287450D01*
X606177Y-287034D01*
X603972Y-287867D01*
X602082Y-289533D01*
X600822Y-292034D01*
X600192Y-295367D01*
X600822Y-298700D01*
X602082Y-301201D01*
X603972Y-302867D01*
X606177Y-303700D01*
X608382Y-303283D01*
X610272Y-302034D01*
X611532Y-300367D01*
G01X651212Y-283400D02*
Y-291400D01*
X655212D01*
G01X663012D02*
Y-286067D01*
G01Y-287000D02*
X662612Y-286467D01*
X662012Y-286200D01*
X661312Y-286067D01*
X660612Y-286333D01*
X660012Y-286867D01*
X659612Y-287667D01*
X659412Y-288733D01*
X659612Y-289800D01*
X660012Y-290600D01*
X660612Y-291133D01*
X661312Y-291400D01*
X662012Y-291267D01*
X662612Y-290867D01*
X663012Y-290334D01*
G01X667112Y-293800D02*
X667712Y-294067D01*
X668512Y-293800D01*
X669012Y-293267D01*
X669412Y-292600D01*
X670012Y-290467D01*
X671312Y-286067D01*
G01X668112D02*
X670012Y-290467D01*
G01X675712Y-287800D02*
X678912D01*
X678612Y-286867D01*
X678112Y-286333D01*
X677412Y-286067D01*
X676712Y-286200D01*
X676112Y-286600D01*
X675712Y-287533D01*
X675512Y-288334D01*
Y-289133D01*
X675712Y-289933D01*
X676212Y-290733D01*
X676812Y-291267D01*
X677512Y-291400D01*
X678212Y-291133D01*
X678912Y-290334D01*
G01X683812Y-291400D02*
Y-286067D01*
G01Y-287133D02*
X684312Y-286600D01*
X684812Y-286200D01*
X685512Y-286067D01*
X686012Y-286200D01*
X686612Y-286600D01*
G01X673512Y-333400D02*
X675912D01*
G01X674712D02*
Y-341400D01*
G01X673512D02*
X675912D01*
G01X681312D02*
Y-336067D01*
G01Y-337133D02*
X681812Y-336600D01*
X682312Y-336200D01*
X683012Y-336067D01*
X683512Y-336200D01*
X684112Y-336600D01*
G01X689212Y-337800D02*
X692412D01*
X692112Y-336867D01*
X691612Y-336333D01*
X690912Y-336067D01*
X690212Y-336200D01*
X689612Y-336600D01*
X689212Y-337533D01*
X689012Y-338334D01*
Y-339133D01*
X689212Y-339933D01*
X689712Y-340733D01*
X690312Y-341267D01*
X691012Y-341400D01*
X691712Y-341133D01*
X692412Y-340334D01*
G01X697012Y-341400D02*
Y-336067D01*
G01Y-337400D02*
X697412Y-336733D01*
X698012Y-336200D01*
X698812Y-336067D01*
X699512Y-336200D01*
X700112Y-336733D01*
X700412Y-337667D01*
Y-341400D01*
G01X705212Y-337800D02*
X708412D01*
X708112Y-336867D01*
X707612Y-336333D01*
X706912Y-336067D01*
X706212Y-336200D01*
X705612Y-336600D01*
X705212Y-337533D01*
X705012Y-338334D01*
Y-339133D01*
X705212Y-339933D01*
X705712Y-340733D01*
X706312Y-341267D01*
X707012Y-341400D01*
X707712Y-341133D01*
X708412Y-340334D01*
G01X670212Y-316400D02*
Y-308400D01*
X672612D01*
X673412Y-308800D01*
X674012Y-309733D01*
X674212Y-310800D01*
X674012Y-311867D01*
X673512Y-312667D01*
X672612Y-313067D01*
X670212D01*
G01X677712Y-316400D02*
X680212Y-308400D01*
X682712Y-316400D01*
G01X681812Y-313600D02*
X678612D01*
G01X685912Y-316400D02*
Y-308400D01*
X690512Y-316400D01*
Y-308400D01*
G01X698212Y-316400D02*
X694212D01*
Y-308400D01*
X698212D01*
G01X696612Y-312267D02*
X694212D01*
G01X702212Y-308400D02*
Y-316400D01*
X706212D01*
G01X777812Y-334733D02*
X778412Y-333933D01*
X779112Y-333533D01*
X779912Y-333400D01*
X780912Y-333667D01*
X781612Y-334333D01*
X781812Y-335133D01*
X781712Y-335934D01*
X781312Y-336600D01*
X779312Y-337933D01*
X778412Y-338867D01*
X777812Y-340200D01*
X777612Y-341400D01*
X781812D01*
G01X787712Y-333400D02*
X786912Y-333667D01*
X786312Y-334333D01*
X785912Y-335133D01*
X785612Y-336200D01*
X785512Y-337400D01*
X785612Y-338600D01*
X785912Y-339667D01*
X786312Y-340467D01*
X786912Y-341133D01*
X787712Y-341400D01*
X788512Y-341133D01*
X789112Y-340467D01*
X789512Y-339667D01*
X789812Y-338600D01*
X789912Y-337400D01*
X789812Y-336200D01*
X789512Y-335133D01*
X789112Y-334333D01*
X788512Y-333667D01*
X787712Y-333400D01*
G01X795712Y-341400D02*
Y-333400D01*
X794512Y-335000D01*
G01Y-341400D02*
X796912D01*
G01X801812Y-334733D02*
X802412Y-333933D01*
X803112Y-333533D01*
X803912Y-333400D01*
X804912Y-333667D01*
X805612Y-334333D01*
X805812Y-335133D01*
X805712Y-335934D01*
X805312Y-336600D01*
X803312Y-337933D01*
X802412Y-338867D01*
X801812Y-340200D01*
X801612Y-341400D01*
X805812D01*
G01X809912Y-341667D02*
X813512Y-333400D01*
G01X819712Y-341400D02*
Y-333400D01*
X818512Y-335000D01*
G01Y-341400D02*
X820912D01*
G01X827712Y-333400D02*
X826912Y-333667D01*
X826312Y-334333D01*
X825912Y-335133D01*
X825612Y-336200D01*
X825512Y-337400D01*
X825612Y-338600D01*
X825912Y-339667D01*
X826312Y-340467D01*
X826912Y-341133D01*
X827712Y-341400D01*
X828512Y-341133D01*
X829112Y-340467D01*
X829512Y-339667D01*
X829812Y-338600D01*
X829912Y-337400D01*
X829812Y-336200D01*
X829512Y-335133D01*
X829112Y-334333D01*
X828512Y-333667D01*
X827712Y-333400D01*
G01X833912Y-341667D02*
X837512Y-333400D01*
G01X841512Y-339800D02*
X842112Y-340733D01*
X842912Y-341267D01*
X843812Y-341400D01*
X844612Y-341267D01*
X845412Y-340600D01*
X845912Y-339800D01*
X846012Y-339000D01*
X845812Y-338067D01*
X845112Y-337400D01*
X844412Y-337133D01*
X843512D01*
G01X844412D02*
X845012Y-336733D01*
X845512Y-336067D01*
X845712Y-335267D01*
X845512Y-334467D01*
X845012Y-333800D01*
X844112Y-333400D01*
X843212Y-333533D01*
X842312Y-334067D01*
G01X851712Y-341400D02*
Y-333400D01*
X850512Y-335000D01*
G01Y-341400D02*
X852912D01*
G01X777512Y-316400D02*
Y-308400D01*
X779512D01*
X780312Y-308800D01*
X780912Y-309333D01*
X781412Y-310133D01*
X781812Y-311067D01*
X781912Y-312400D01*
X781812Y-313733D01*
X781412Y-314667D01*
X780912Y-315467D01*
X780312Y-316000D01*
X779512Y-316400D01*
X777512D01*
G01X785212D02*
X787712Y-308400D01*
X790212Y-316400D01*
G01X789312Y-313600D02*
X786112D01*
G01X795712Y-308400D02*
X794912Y-308667D01*
X794312Y-309333D01*
X793912Y-310133D01*
X793612Y-311200D01*
X793512Y-312400D01*
X793612Y-313600D01*
X793912Y-314667D01*
X794312Y-315467D01*
X794912Y-316133D01*
X795712Y-316400D01*
X796512Y-316133D01*
X797112Y-315467D01*
X797512Y-314667D01*
X797812Y-313600D01*
X797912Y-312400D01*
X797812Y-311200D01*
X797512Y-310133D01*
X797112Y-309333D01*
X796512Y-308667D01*
X795712Y-308400D01*
G01X803712D02*
Y-316400D01*
G01X801412Y-308400D02*
X806012D01*
G01X809812Y-313067D02*
X810512Y-312133D01*
X811112Y-311600D01*
X811912Y-311333D01*
X812612Y-311600D01*
X813112Y-312133D01*
X813512Y-312933D01*
X813612Y-313867D01*
X813512Y-314667D01*
X813112Y-315467D01*
X812512Y-316133D01*
X811812Y-316400D01*
X811012Y-316133D01*
X810312Y-315334D01*
X809912Y-314133D01*
X809812Y-312800D01*
X810012Y-311067D01*
X810312Y-310133D01*
X810812Y-309200D01*
X811512Y-308533D01*
X812212Y-308400D01*
X812912Y-308667D01*
X813412Y-309333D01*
G01X817112Y-316400D02*
Y-308400D01*
X819712Y-315067D01*
X822312Y-308400D01*
Y-316400D01*
G01X827712Y-308400D02*
Y-316400D01*
G01X825412Y-308400D02*
X830012D01*
G01X833612Y-316400D02*
Y-308400D01*
G01X837812D02*
Y-316400D01*
G01Y-312400D02*
X833612D01*
G01X843712Y-316400D02*
X844412Y-316267D01*
X845212Y-315867D01*
X845712Y-315200D01*
X845912Y-314267D01*
X845712Y-313334D01*
X845112Y-312533D01*
X844212Y-312133D01*
X843212D01*
X842612Y-311867D01*
X842112Y-311200D01*
X841912Y-310267D01*
X842212Y-309333D01*
X842912Y-308667D01*
X843712Y-308400D01*
X844512Y-308667D01*
X845212Y-309333D01*
X845512Y-310267D01*
X845312Y-311200D01*
X844812Y-311867D01*
X844212Y-312133D01*
X843212D01*
X842312Y-312533D01*
X841712Y-313334D01*
X841512Y-314267D01*
X841712Y-315200D01*
X842212Y-315867D01*
X843012Y-316267D01*
X843712Y-316400D01*
G01X853912Y-309067D02*
X853312Y-308667D01*
X852612Y-308400D01*
X851812D01*
X850912Y-308800D01*
X850212Y-309467D01*
X849712Y-310267D01*
X849312Y-311600D01*
X849212Y-312800D01*
X849412Y-314000D01*
X849712Y-314800D01*
X850312Y-315600D01*
X851012Y-316133D01*
X851712Y-316400D01*
X852412D01*
X853112Y-316133D01*
X853712Y-315733D01*
X854212Y-315200D01*
G01X859712Y-308400D02*
X858912Y-308667D01*
X858312Y-309333D01*
X857912Y-310133D01*
X857612Y-311200D01*
X857512Y-312400D01*
X857612Y-313600D01*
X857912Y-314667D01*
X858312Y-315467D01*
X858912Y-316133D01*
X859712Y-316400D01*
X860512Y-316133D01*
X861112Y-315467D01*
X861512Y-314667D01*
X861812Y-313600D01*
X861912Y-312400D01*
X861812Y-311200D01*
X861512Y-310133D01*
X861112Y-309333D01*
X860512Y-308667D01*
X859712Y-308400D01*
G01X791250Y816550D02*
Y822850D01*
X790310Y821590D01*
G01Y816550D02*
X792190D01*
G01X797550D02*
X798098Y816655D01*
X798725Y816970D01*
X799117Y817495D01*
X799273Y818230D01*
X799117Y818965D01*
X798647Y819595D01*
X797942Y819910D01*
X797158D01*
X796688Y820120D01*
X796297Y820645D01*
X796140Y821380D01*
X796375Y822115D01*
X796923Y822640D01*
X797550Y822850D01*
X798177Y822640D01*
X798725Y822115D01*
X798960Y821380D01*
X798803Y820645D01*
X798412Y820120D01*
X797942Y819910D01*
X797158D01*
X796453Y819595D01*
X795983Y818965D01*
X795827Y818230D01*
X795983Y817495D01*
X796375Y816970D01*
X797002Y816655D01*
X797550Y816550D01*
G01X802362Y821800D02*
X802832Y822430D01*
X803380Y822745D01*
X804007Y822850D01*
X804790Y822640D01*
X805338Y822115D01*
X805495Y821485D01*
X805417Y820855D01*
X805103Y820330D01*
X803537Y819280D01*
X802832Y818545D01*
X802362Y817495D01*
X802205Y816550D01*
X805495D01*
G01X808818Y817285D02*
X809367Y816760D01*
X809993Y816550D01*
X810620Y816760D01*
X811168Y817390D01*
X811560Y818335D01*
X811717Y819280D01*
Y820435D01*
X811560Y821380D01*
X811168Y822220D01*
X810698Y822640D01*
X810150Y822850D01*
X809523Y822640D01*
X809053Y822220D01*
X808740Y821590D01*
X808583Y820750D01*
X808740Y820015D01*
X809132Y819280D01*
X809602Y818860D01*
X810150Y818755D01*
X810777Y818965D01*
X811247Y819490D01*
X811717Y820435D01*
G01X815118Y817285D02*
X815667Y816760D01*
X816293Y816550D01*
X816920Y816760D01*
X817468Y817390D01*
X817860Y818335D01*
X818017Y819280D01*
Y820435D01*
X817860Y821380D01*
X817468Y822220D01*
X816998Y822640D01*
X816450Y822850D01*
X815823Y822640D01*
X815353Y822220D01*
X815040Y821590D01*
X814883Y820750D01*
X815040Y820015D01*
X815432Y819280D01*
X815902Y818860D01*
X816450Y818755D01*
X817077Y818965D01*
X817547Y819490D01*
X818017Y820435D01*
G01X822750Y816340D02*
X822593Y816445D01*
Y816655D01*
X822750Y816760D01*
X822907Y816655D01*
Y816445D01*
X822750Y816340D01*
G01X827562Y819175D02*
X828110Y819910D01*
X828580Y820330D01*
X829207Y820540D01*
X829755Y820330D01*
X830147Y819910D01*
X830460Y819280D01*
X830538Y818545D01*
X830460Y817915D01*
X830147Y817285D01*
X829677Y816760D01*
X829128Y816550D01*
X828502Y816760D01*
X827953Y817390D01*
X827640Y818335D01*
X827562Y819385D01*
X827718Y820750D01*
X827953Y821485D01*
X828345Y822220D01*
X828893Y822745D01*
X829442Y822850D01*
X829990Y822640D01*
X830382Y822115D01*
G01X835350Y822850D02*
X834723Y822640D01*
X834253Y822115D01*
X833940Y821485D01*
X833705Y820645D01*
X833627Y819700D01*
X833705Y818755D01*
X833940Y817915D01*
X834253Y817285D01*
X834723Y816760D01*
X835350Y816550D01*
X835977Y816760D01*
X836447Y817285D01*
X836760Y817915D01*
X836995Y818755D01*
X837073Y819700D01*
X836995Y820645D01*
X836760Y821485D01*
X836447Y822115D01*
X835977Y822640D01*
X835350Y822850D01*
G01X799712Y-283400D02*
Y-291400D01*
G01X797412Y-283400D02*
X802012D01*
G01X805812Y-288067D02*
X806512Y-287133D01*
X807112Y-286600D01*
X807912Y-286333D01*
X808612Y-286600D01*
X809112Y-287133D01*
X809512Y-287933D01*
X809612Y-288867D01*
X809512Y-289667D01*
X809112Y-290467D01*
X808512Y-291133D01*
X807812Y-291400D01*
X807012Y-291133D01*
X806312Y-290334D01*
X805912Y-289133D01*
X805812Y-287800D01*
X806012Y-286067D01*
X806312Y-285133D01*
X806812Y-284200D01*
X807512Y-283533D01*
X808212Y-283400D01*
X808912Y-283667D01*
X809412Y-284333D01*
G01X813112Y-291400D02*
Y-283400D01*
X815712Y-290067D01*
X818312Y-283400D01*
Y-291400D01*
G01X820712Y-294067D02*
X826712D01*
G01X831712Y-283400D02*
Y-291400D01*
G01X829412Y-283400D02*
X834012D01*
G01X838312Y-291400D02*
Y-286067D01*
G01Y-287133D02*
X838812Y-286600D01*
X839312Y-286200D01*
X840012Y-286067D01*
X840512Y-286200D01*
X841112Y-286600D01*
G01X849512Y-291400D02*
Y-286067D01*
G01Y-287000D02*
X849112Y-286467D01*
X848512Y-286200D01*
X847812Y-286067D01*
X847112Y-286333D01*
X846512Y-286867D01*
X846112Y-287667D01*
X845912Y-288733D01*
X846112Y-289800D01*
X846512Y-290600D01*
X847112Y-291133D01*
X847812Y-291400D01*
X848512Y-291267D01*
X849112Y-290867D01*
X849512Y-290334D01*
G01X853612Y-293800D02*
X854212Y-294067D01*
X855012Y-293800D01*
X855512Y-293267D01*
X855912Y-292600D01*
X856512Y-290467D01*
X857812Y-286067D01*
G01X854612D02*
X856512Y-290467D01*
G01X860712Y-294067D02*
X866712D01*
G01X872512Y-287133D02*
X872912Y-286733D01*
X873212Y-286067D01*
X873412Y-285133D01*
X873212Y-284333D01*
X872812Y-283800D01*
X872112Y-283400D01*
X869412D01*
Y-291400D01*
X872712D01*
X873412Y-290867D01*
X873812Y-290067D01*
X874012Y-289133D01*
X873812Y-288200D01*
X873212Y-287400D01*
X872512Y-287133D01*
X869412D01*
G01X877712Y-291400D02*
Y-283400D01*
X880112D01*
X880912Y-283800D01*
X881512Y-284733D01*
X881712Y-285800D01*
X881512Y-286867D01*
X881012Y-287667D01*
X880112Y-288067D01*
X877712D01*
G01X896912Y-334067D02*
X896312Y-333667D01*
X895612Y-333400D01*
X894812D01*
X893912Y-333800D01*
X893212Y-334467D01*
X892712Y-335267D01*
X892312Y-336600D01*
X892212Y-337800D01*
X892412Y-339000D01*
X892712Y-339800D01*
X893312Y-340600D01*
X894012Y-341133D01*
X894712Y-341400D01*
X895412D01*
X896112Y-341133D01*
X896712Y-340733D01*
X897212Y-340200D01*
G01X922212Y-341400D02*
Y-333400D01*
X921012Y-335000D01*
G01Y-341400D02*
X923412D01*
G01X928312Y-338067D02*
X929012Y-337133D01*
X929612Y-336600D01*
X930412Y-336333D01*
X931112Y-336600D01*
X931612Y-337133D01*
X932012Y-337933D01*
X932112Y-338867D01*
X932012Y-339667D01*
X931612Y-340467D01*
X931012Y-341133D01*
X930312Y-341400D01*
X929512Y-341133D01*
X928812Y-340334D01*
X928412Y-339133D01*
X928312Y-337800D01*
X928512Y-336067D01*
X928812Y-335133D01*
X929312Y-334200D01*
X930012Y-333533D01*
X930712Y-333400D01*
X931412Y-333667D01*
X931912Y-334333D01*
G01X938935Y-120100D02*
Y-145100D01*
X926965D01*
G01X931375Y-133017D02*
X938935D01*
G01X930965Y79300D02*
Y104300D01*
X942935D01*
G01X938525Y92217D02*
X930965D01*
G01X931235Y434500D02*
Y409500D01*
X919265D01*
G01X923675Y421583D02*
X931235D01*
G01X923265Y633900D02*
Y658900D01*
X935235D01*
G01X930825Y646817D02*
X923265D01*
G01X1747283Y-198031D02*
G03I-7874J0D01*
G01X1745315Y-150787D02*
G03I-5906J0D01*
G01X1747283Y727951D02*
G03I-7874J0D01*
G01X1807815Y233368D02*
X1808340Y233917D01*
X1808550Y234543D01*
X1808340Y235170D01*
X1807710Y235718D01*
X1806765Y236110D01*
X1805820Y236267D01*
X1804665D01*
X1803720Y236110D01*
X1802880Y235718D01*
X1802460Y235248D01*
X1802250Y234700D01*
X1802460Y234073D01*
X1802880Y233603D01*
X1803510Y233290D01*
X1804350Y233133D01*
X1805085Y233290D01*
X1805820Y233682D01*
X1806240Y234152D01*
X1806345Y234700D01*
X1806135Y235327D01*
X1805610Y235797D01*
X1804665Y236267D01*
G01X1805925Y239512D02*
X1805190Y240060D01*
X1804770Y240530D01*
X1804560Y241157D01*
X1804770Y241705D01*
X1805190Y242097D01*
X1805820Y242410D01*
X1806555Y242488D01*
X1807185Y242410D01*
X1807815Y242097D01*
X1808340Y241627D01*
X1808550Y241078D01*
X1808340Y240452D01*
X1807710Y239903D01*
X1806765Y239590D01*
X1805715Y239512D01*
X1804350Y239668D01*
X1803615Y239903D01*
X1802880Y240295D01*
X1802355Y240843D01*
X1802250Y241392D01*
X1802460Y241940D01*
X1802985Y242332D01*
G01X1807605Y245577D02*
X1808130Y246047D01*
X1808445Y246595D01*
X1808550Y247300D01*
X1808340Y248005D01*
X1807920Y248553D01*
X1807185Y248945D01*
X1806345Y249023D01*
X1805505Y248867D01*
X1804980Y248475D01*
X1804560Y247927D01*
X1804455Y247378D01*
X1804560Y246830D01*
X1804980Y246125D01*
X1802250Y246360D01*
Y248475D01*
G01X1807290Y251877D02*
X1808025Y252347D01*
X1808445Y252973D01*
X1808550Y253678D01*
X1808445Y254305D01*
X1807920Y254932D01*
X1807290Y255323D01*
X1806660Y255402D01*
X1805925Y255245D01*
X1805400Y254697D01*
X1805190Y254148D01*
Y253443D01*
G01Y254148D02*
X1804875Y254618D01*
X1804350Y255010D01*
X1803720Y255167D01*
X1803090Y255010D01*
X1802565Y254618D01*
X1802250Y253913D01*
X1802355Y253208D01*
X1802775Y252503D01*
G01X1808760Y259900D02*
X1808655Y259743D01*
X1808445D01*
X1808340Y259900D01*
X1808445Y260057D01*
X1808655D01*
X1808760Y259900D01*
G01X1807605Y264477D02*
X1808130Y264947D01*
X1808445Y265495D01*
X1808550Y266200D01*
X1808340Y266905D01*
X1807920Y267453D01*
X1807185Y267845D01*
X1806345Y267923D01*
X1805505Y267767D01*
X1804980Y267375D01*
X1804560Y266827D01*
X1804455Y266278D01*
X1804560Y265730D01*
X1804980Y265025D01*
X1802250Y265260D01*
Y267375D01*
G01X1803300Y271012D02*
X1802670Y271482D01*
X1802355Y272030D01*
X1802250Y272657D01*
X1802460Y273440D01*
X1802985Y273988D01*
X1803615Y274145D01*
X1804245Y274067D01*
X1804770Y273753D01*
X1805820Y272187D01*
X1806555Y271482D01*
X1807605Y271012D01*
X1808550Y270855D01*
Y274145D01*
G01X1827875Y64635D02*
X2072284D01*
Y-219380D01*
X1827875D01*
Y64635D01*
G01X1875119Y-83790D02*
G03I-5906J0D01*
G01X1876536Y14713D02*
G03I-7874J0D01*
G01X1883387Y-157018D02*
X1892835D01*
G02Y-164892I0J-3937D01*
G01X1883387D01*
G01X1912520Y-157018D02*
X1921969D01*
G01X1912520D02*
G03Y-164892I0J-3937D01*
G01X1921969D01*
M02*
